FILE_TYPE = MACRO_DRAWING;
SET COLOR_WIRE YELLOW;
SET COLOR_PROP MONO;
SET COLOR_DOT WHITE;
SET COLOR_ARC YELLOW;
SET COLOR_BODY GREEN;
SET COLOR_NOTE MONO;
SET PROP_DISPLAY VALUE;
SET PAGE_NUMBER P255;
FORCEADD GND..1
(-4100 3200);
FORCEPROP 3 LASTPIN (-4100 3250) SIG_NAME GND\g
J 0
(-4090 3260);
DISPLAY 0.659574 (-4090 3260);
PAINT MONO (-4090 3260);
DISPLAY INVISIBLE (-4090 3260);
FORCEPROP 2 LAST CDS_LIB mstr_symbols
J 0
(-4100 3200);
PAINT MONO (-4100 3200);
DISPLAY INVISIBLE (-4100 3200);
FORCEPROP 1 LAST PATH I10
J 0
(-4025 3200);
DISPLAY 0.872340 (-4025 3200);
PAINT AQUA (-4025 3200);
DISPLAY INVISIBLE (-4025 3200);
FORCEPROP 1 LAST VOLTAGE 0.0V
J 0
(-4161 3173);
DISPLAY 0.340426 (-4161 3173);
PAINT SKYBLUE (-4161 3173);
DISPLAY INVISIBLE (-4161 3173);
FORCEPROP 1 LAST SIZE 1B
J 0
(-4066 3191);
DISPLAY 0.872340 (-4066 3191);
PAINT AQUA (-4066 3191);
DISPLAY INVISIBLE (-4066 3191);
FORCEPROP 1 LAST BODY_TYPE PLUMBING
J 0
(-4161 3173);
DISPLAY 0.340426 (-4161 3173);
PAINT GREEN (-4161 3173);
DISPLAY INVISIBLE (-4161 3173);
FORCEPROP 1 LAST HDL_POWER GND
J 0
(-4141 3391);
DISPLAY 0.872340 (-4141 3391);
PAINT GREEN (-4141 3391);
DISPLAY INVISIBLE (-4141 3391);
FORCEADD CAP..1
(-4500 3450);
FORCEPROP 1 LAST LOCATION C25W73
J 0
(-4450 3550);
DISPLAY 0.617021 (-4450 3550);
PAINT AQUA (-4450 3550);
FORCEPROP 1 LASTPIN (-4500 3350) $PN 2
J 0
(-4490 3330);
DISPLAY 0.787234 (-4490 3330);
PAINT ORANGE (-4490 3330);
FORCEPROP 1 LAST VOLTAGE 50V
J 0
(-4450 3450);
DISPLAY 0.617021 (-4450 3450);
PAINT SKYBLUE (-4450 3450);
FORCEPROP 1 LAST TOLERANCE 5%
J 0
(-4450 3400);
DISPLAY 0.617021 (-4450 3400);
PAINT SKYBLUE (-4450 3400);
FORCEPROP 1 LASTPIN (-4500 3550) $PN 1
J 0
(-4490 3530);
DISPLAY 0.787234 (-4490 3530);
PAINT ORANGE (-4490 3530);
FORCEPROP 1 LAST VALUE 12.0PF
J 0
(-4450 3500);
DISPLAY 0.617021 (-4450 3500);
PAINT SKYBLUE (-4450 3500);
FORCEPROP 1 LAST MATERIAL COG
J 0
(-4450 3350);
DISPLAY 0.617021 (-4450 3350);
PAINT SKYBLUE (-4450 3350);
FORCEPROP 1 LAST PART_NUMBER A36095-043
J 0
(-4450 3300);
DISPLAY 0.617021 (-4450 3300);
PAINT BLUE (-4450 3300);
FORCEPROP 1 LAST PACK_TYPE 0402LF
J 0
(-4450 3250);
DISPLAY 0.617021 (-4450 3250);
PAINT SKYBLUE (-4450 3250);
FORCEPROP 0 LAST GROUP AST2500
J 0
(-4447 3210);
DISPLAY 0.638298 (-4447 3210);
PAINT BROWN (-4447 3210);
DISPLAY BOTH (-4447 3210);
FORCEPROP 2 LAST CDS_LOCATION C25W73
J 0
(-4450 3550);
DISPLAY 0.617021 (-4450 3550);
PAINT AQUA (-4450 3550);
DISPLAY INVISIBLE (-4450 3550);
FORCEPROP 1 LAST PATH I11
J 0
(-4450 3600);
DISPLAY 0.978723 (-4450 3600);
PAINT WHITE (-4450 3600);
DISPLAY INVISIBLE (-4450 3600);
FORCEPROP 2 LAST CDS_LIB mstr_discrete
J 0
(-4500 3450);
PAINT ORANGE (-4500 3450);
DISPLAY INVISIBLE (-4500 3450);
FORCEPROP 2 LAST ROOM LBG
J 0
(-4450 3600);
DISPLAY 1.021277 (-4450 3600);
PAINT ORANGE (-4450 3600);
DISPLAY INVISIBLE (-4450 3600);
FORCEPROP 2 LAST BOM_COST LBG_UART
J 0
(-4450 3650);
DISPLAY 1.021277 (-4450 3650);
PAINT ORANGE (-4450 3650);
DISPLAY INVISIBLE (-4450 3650);
FORCEPROP 2 LAST SEC_TYPE 0402LF
J 0
(-4450 3650);
DISPLAY 1.021277 (-4450 3650);
PAINT ORANGE (-4450 3650);
DISPLAY INVISIBLE (-4450 3650);
FORCEPROP 2 LAST SEC 1
J 0
(-4450 3650);
PAINT MONO (-4450 3650);
DISPLAY INVISIBLE (-4450 3650);
FORCEADD U74AHCT1G125G-AL5-R-GP-U..1
(-4350 5100);
FORCEPROP 1 LAST LOCATION U25W7
J 0
(-4500 5250);
DISPLAY 0.617021 (-4500 5250);
PAINT GREEN (-4500 5250);
FORCEPROP 2 LASTPIN (-4050 5200) $PN 5
J 0
(-4040 5210);
DISPLAY 0.808511 (-4040 5210);
PAINT ORANGE (-4040 5210);
FORCEPROP 2 LASTPIN (-4650 5100) $PN 2
J 2
(-4660 5110);
DISPLAY 0.808511 (-4660 5110);
PAINT ORANGE (-4660 5110);
FORCEPROP 2 LASTPIN (-4650 5000) $PN 3
J 2
(-4660 5010);
DISPLAY 0.808511 (-4660 5010);
PAINT ORANGE (-4660 5010);
FORCEPROP 2 LASTPIN (-4650 5200) $PN 1
J 2
(-4660 5210);
DISPLAY 0.808511 (-4660 5210);
PAINT ORANGE (-4660 5210);
FORCEPROP 2 LASTPIN (-4050 5000) $PN 4
J 0
(-4040 5010);
DISPLAY 0.808511 (-4040 5010);
PAINT ORANGE (-4040 5010);
FORCEPROP 1 LAST VALUE U74AHCT1G125G-AL5-R-GP-U
J 0
(-4500 4900);
DISPLAY 0.617021 (-4500 4900);
PAINT GREEN (-4500 4900);
FORCEPROP 0 LAST GROUP AST2500
J 0
(-4485 4853);
DISPLAY 0.638298 (-4485 4853);
PAINT BROWN (-4485 4853);
DISPLAY BOTH (-4485 4853);
FORCEPROP 1 LAST CDS_LMAN_SYM_OUTLINE -150,150,150,-150
J 0
(-4350 5100);
DISPLAY 0.468085 (-4350 5100);
PAINT GREEN (-4350 5100);
DISPLAY INVISIBLE (-4350 5100);
FORCEPROP 1 LAST PATH I111
J 0
(-4350 5100);
DISPLAY 0.617021 (-4350 5100);
PAINT GREEN (-4350 5100);
DISPLAY INVISIBLE (-4350 5100);
FORCEPROP 2 LAST CDS_LIB w_hdl
J 0
(-4350 5100);
PAINT MONO (-4350 5100);
DISPLAY INVISIBLE (-4350 5100);
FORCEPROP 1 LAST PART_NUMBER 73.1G125.D0G
J 0
(-4350 5100);
DISPLAY 0.617021 (-4350 5100);
PAINT GREEN (-4350 5100);
DISPLAY INVISIBLE (-4350 5100);
FORCEPROP 2 LAST SEC_TYPE TTL-G4
J 0
(-4500 5300);
DISPLAY 1.021277 (-4500 5300);
PAINT ORANGE (-4500 5300);
DISPLAY INVISIBLE (-4500 5300);
FORCEPROP 2 LAST SEC 1
J 0
(-4500 5300);
DISPLAY 0.680851 (-4500 5300);
PAINT MONO (-4500 5300);
DISPLAY INVISIBLE (-4500 5300);
FORCEPROP 1 LAST PACK_TYPE TTL-G4
J 0
(-4350 5100);
DISPLAY 0.617021 (-4350 5100);
PAINT GREEN (-4350 5100);
DISPLAY INVISIBLE (-4350 5100);
FORCEADD U74AHCT1G125G-AL5-R-GP-U..1
(-4350 4550);
FORCEPROP 1 LAST VALUE U74AHCT1G125G-AL5-R-GP-U
J 0
(-4500 4350);
DISPLAY 0.617021 (-4500 4350);
PAINT GREEN (-4500 4350);
FORCEPROP 2 LASTPIN (-4650 4650) $PN 1
J 2
(-4660 4660);
DISPLAY 0.808511 (-4660 4660);
PAINT ORANGE (-4660 4660);
FORCEPROP 2 LASTPIN (-4650 4550) $PN 2
J 2
(-4660 4560);
DISPLAY 0.808511 (-4660 4560);
PAINT ORANGE (-4660 4560);
FORCEPROP 2 LASTPIN (-4650 4450) $PN 3
J 2
(-4660 4460);
DISPLAY 0.808511 (-4660 4460);
PAINT ORANGE (-4660 4460);
FORCEPROP 1 LAST LOCATION U25W8
J 0
(-4500 4700);
DISPLAY 0.617021 (-4500 4700);
PAINT GREEN (-4500 4700);
FORCEPROP 2 LASTPIN (-4050 4450) $PN 4
J 0
(-4040 4460);
DISPLAY 0.808511 (-4040 4460);
PAINT ORANGE (-4040 4460);
FORCEPROP 0 LAST GROUP AST2500
J 0
(-4485 4303);
DISPLAY 0.638298 (-4485 4303);
PAINT BROWN (-4485 4303);
DISPLAY BOTH (-4485 4303);
FORCEPROP 2 LASTPIN (-4050 4650) $PN 5
J 0
(-4040 4660);
DISPLAY 0.808511 (-4040 4660);
PAINT ORANGE (-4040 4660);
FORCEPROP 1 LAST PATH I112
J 0
(-4350 4550);
DISPLAY 0.617021 (-4350 4550);
PAINT GREEN (-4350 4550);
DISPLAY INVISIBLE (-4350 4550);
FORCEPROP 1 LAST CDS_LMAN_SYM_OUTLINE -150,150,150,-150
J 0
(-4350 4550);
DISPLAY 0.468085 (-4350 4550);
PAINT GREEN (-4350 4550);
DISPLAY INVISIBLE (-4350 4550);
FORCEPROP 2 LAST CDS_LIB w_hdl
J 0
(-4350 4550);
PAINT MONO (-4350 4550);
DISPLAY INVISIBLE (-4350 4550);
FORCEPROP 1 LAST PART_NUMBER 73.1G125.D0G
J 0
(-4350 4550);
DISPLAY 0.617021 (-4350 4550);
PAINT GREEN (-4350 4550);
DISPLAY INVISIBLE (-4350 4550);
FORCEPROP 2 LAST SEC_TYPE TTL-G4
J 0
(-4500 4750);
DISPLAY 1.021277 (-4500 4750);
PAINT ORANGE (-4500 4750);
DISPLAY INVISIBLE (-4500 4750);
FORCEPROP 2 LAST SEC 1
J 0
(-4500 4750);
DISPLAY 0.680851 (-4500 4750);
PAINT MONO (-4500 4750);
DISPLAY INVISIBLE (-4500 4750);
FORCEPROP 1 LAST PACK_TYPE TTL-G4
J 0
(-4350 4550);
DISPLAY 0.617021 (-4350 4550);
PAINT GREEN (-4350 4550);
DISPLAY INVISIBLE (-4350 4550);
FORCEADD GND..1
(-4750 4350);
FORCEPROP 3 LASTPIN (-4750 4400) SIG_NAME GND\g
J 0
(-4740 4410);
DISPLAY 0.659574 (-4740 4410);
PAINT MONO (-4740 4410);
DISPLAY INVISIBLE (-4740 4410);
FORCEPROP 1 LAST PATH I113
J 0
(-4675 4350);
DISPLAY 0.872340 (-4675 4350);
PAINT AQUA (-4675 4350);
DISPLAY INVISIBLE (-4675 4350);
FORCEPROP 1 LAST SIZE 1B
J 0
(-4716 4341);
DISPLAY 0.872340 (-4716 4341);
PAINT AQUA (-4716 4341);
DISPLAY INVISIBLE (-4716 4341);
FORCEPROP 1 LAST VOLTAGE 0.0V
J 0
(-4811 4323);
DISPLAY 0.340426 (-4811 4323);
PAINT SKYBLUE (-4811 4323);
DISPLAY INVISIBLE (-4811 4323);
FORCEPROP 2 LAST CDS_LIB mstr_symbols
J 0
(-4750 4350);
PAINT MONO (-4750 4350);
DISPLAY INVISIBLE (-4750 4350);
FORCEPROP 1 LAST BODY_TYPE PLUMBING
J 0
(-4811 4323);
DISPLAY 0.340426 (-4811 4323);
PAINT GREEN (-4811 4323);
DISPLAY INVISIBLE (-4811 4323);
FORCEPROP 1 LAST HDL_POWER GND
J 0
(-4791 4541);
DISPLAY 0.872340 (-4791 4541);
PAINT GREEN (-4791 4541);
DISPLAY INVISIBLE (-4791 4541);
FORCEADD GND..1
(-4750 4600);
FORCEPROP 3 LASTPIN (-4750 4650) SIG_NAME GND\g
J 0
(-4740 4660);
DISPLAY 0.659574 (-4740 4660);
PAINT MONO (-4740 4660);
DISPLAY INVISIBLE (-4740 4660);
FORCEPROP 1 LAST SIZE 1B
J 0
(-4716 4591);
DISPLAY 0.872340 (-4716 4591);
PAINT AQUA (-4716 4591);
DISPLAY INVISIBLE (-4716 4591);
FORCEPROP 1 LAST VOLTAGE 0.0V
J 0
(-4811 4573);
DISPLAY 0.340426 (-4811 4573);
PAINT SKYBLUE (-4811 4573);
DISPLAY INVISIBLE (-4811 4573);
FORCEPROP 2 LAST CDS_LIB mstr_symbols
J 0
(-4750 4600);
PAINT MONO (-4750 4600);
DISPLAY INVISIBLE (-4750 4600);
FORCEPROP 1 LAST PATH I114
J 0
(-4675 4600);
DISPLAY 0.872340 (-4675 4600);
PAINT AQUA (-4675 4600);
DISPLAY INVISIBLE (-4675 4600);
FORCEPROP 1 LAST BODY_TYPE PLUMBING
J 0
(-4811 4573);
DISPLAY 0.340426 (-4811 4573);
PAINT GREEN (-4811 4573);
DISPLAY INVISIBLE (-4811 4573);
FORCEPROP 1 LAST HDL_POWER GND
J 0
(-4791 4791);
DISPLAY 0.872340 (-4791 4791);
PAINT GREEN (-4791 4791);
DISPLAY INVISIBLE (-4791 4791);
FORCEADD GND..1
(-4750 5150);
FORCEPROP 3 LASTPIN (-4750 5200) SIG_NAME GND\g
J 0
(-4740 5210);
DISPLAY 0.659574 (-4740 5210);
PAINT MONO (-4740 5210);
DISPLAY INVISIBLE (-4740 5210);
FORCEPROP 1 LAST PATH I115
J 0
(-4675 5150);
DISPLAY 0.872340 (-4675 5150);
PAINT AQUA (-4675 5150);
DISPLAY INVISIBLE (-4675 5150);
FORCEPROP 2 LAST CDS_LIB mstr_symbols
J 0
(-4750 5150);
PAINT MONO (-4750 5150);
DISPLAY INVISIBLE (-4750 5150);
FORCEPROP 1 LAST VOLTAGE 0.0V
J 0
(-4811 5123);
DISPLAY 0.340426 (-4811 5123);
PAINT SKYBLUE (-4811 5123);
DISPLAY INVISIBLE (-4811 5123);
FORCEPROP 1 LAST SIZE 1B
J 0
(-4716 5141);
DISPLAY 0.872340 (-4716 5141);
PAINT AQUA (-4716 5141);
DISPLAY INVISIBLE (-4716 5141);
FORCEPROP 1 LAST BODY_TYPE PLUMBING
J 0
(-4811 5123);
DISPLAY 0.340426 (-4811 5123);
PAINT GREEN (-4811 5123);
DISPLAY INVISIBLE (-4811 5123);
FORCEPROP 1 LAST HDL_POWER GND
J 0
(-4791 5341);
DISPLAY 0.872340 (-4791 5341);
PAINT GREEN (-4791 5341);
DISPLAY INVISIBLE (-4791 5341);
FORCEADD GND..1
(-4750 4900);
FORCEPROP 3 LASTPIN (-4750 4950) SIG_NAME GND\g
J 0
(-4740 4960);
DISPLAY 0.659574 (-4740 4960);
PAINT MONO (-4740 4960);
DISPLAY INVISIBLE (-4740 4960);
FORCEPROP 1 LAST PATH I116
J 0
(-4675 4900);
DISPLAY 0.872340 (-4675 4900);
PAINT AQUA (-4675 4900);
DISPLAY INVISIBLE (-4675 4900);
FORCEPROP 2 LAST CDS_LIB mstr_symbols
J 0
(-4750 4900);
PAINT MONO (-4750 4900);
DISPLAY INVISIBLE (-4750 4900);
FORCEPROP 1 LAST VOLTAGE 0.0V
J 0
(-4811 4873);
DISPLAY 0.340426 (-4811 4873);
PAINT SKYBLUE (-4811 4873);
DISPLAY INVISIBLE (-4811 4873);
FORCEPROP 1 LAST SIZE 1B
J 0
(-4716 4891);
DISPLAY 0.872340 (-4716 4891);
PAINT AQUA (-4716 4891);
DISPLAY INVISIBLE (-4716 4891);
FORCEPROP 1 LAST BODY_TYPE PLUMBING
J 0
(-4811 4873);
DISPLAY 0.340426 (-4811 4873);
PAINT GREEN (-4811 4873);
DISPLAY INVISIBLE (-4811 4873);
FORCEPROP 1 LAST HDL_POWER GND
J 0
(-4791 5091);
DISPLAY 0.872340 (-4791 5091);
PAINT GREEN (-4791 5091);
DISPLAY INVISIBLE (-4791 5091);
FORCEADD W_VCC_CIRCLE..1
(-3850 4700);
FORCEPROP 3 LASTPIN (-3850 4700) SIG_NAME P5V_VGA_D\g
J 0
(-3840 4710);
DISPLAY 0.659574 (-3840 4710);
PAINT MONO (-3840 4710);
DISPLAY INVISIBLE (-3840 4710);
FORCEPROP 1 LAST HDL_POWER P5V_VGA_D
J 1
(-3829 4775);
DISPLAY 0.872340 (-3829 4775);
PAINT ORANGE (-3829 4775);
FORCEPROP 1 LAST CDS_LMAN_SYM_OUTLINE -100,100,100,-100
J 0
(-3850 4700);
DISPLAY 0.468085 (-3850 4700);
PAINT GREEN (-3850 4700);
DISPLAY INVISIBLE (-3850 4700);
FORCEPROP 2 LAST CDS_LIB w_power
J 0
(-3850 4700);
PAINT MONO (-3850 4700);
DISPLAY INVISIBLE (-3850 4700);
FORCEPROP 1 LAST PATH I117
J 0
(-3850 4700);
DISPLAY 0.617021 (-3850 4700);
PAINT GREEN (-3850 4700);
DISPLAY INVISIBLE (-3850 4700);
FORCEPROP 1 LAST BODY_TYPE PLUMBING
J 0
(-3838 4694);
DISPLAY 0.340426 (-3838 4694);
PAINT GREEN (-3838 4694);
DISPLAY INVISIBLE (-3838 4694);
FORCEADD CAP_A..1
R 1
(-3500 4650);
FORCEPROP 1 LAST PART_NUMBER A36096-030
J 0
(-3925 4525);
DISPLAY 0.617021 (-3925 4525);
PAINT BLUE (-3925 4525);
FORCEPROP 1 LAST PACK_TYPE 0402V
J 0
(-3650 4525);
DISPLAY 0.617021 (-3650 4525);
PAINT SKYBLUE (-3650 4525);
FORCEPROP 0 LAST GROUP AST2500
J 0
(-3485 4528);
DISPLAY 0.638298 (-3485 4528);
PAINT BROWN (-3485 4528);
DISPLAY BOTH (-3485 4528);
FORCEPROP 1 LAST VOLTAGE 16V
J 0
(-3650 4575);
DISPLAY 0.617021 (-3650 4575);
PAINT SKYBLUE (-3650 4575);
FORCEPROP 1 LAST LOCATION C25W90
J 0
(-4125 4575);
DISPLAY 0.617021 (-4125 4575);
PAINT AQUA (-4125 4575);
FORCEPROP 1 LAST VALUE 0.1UF
J 0
(-3925 4575);
DISPLAY 0.617021 (-3925 4575);
PAINT SKYBLUE (-3925 4575);
FORCEPROP 1 LASTPIN (-3400 4650) $PN 2
J 0
(-3405 4660);
DISPLAY 0.617021 (-3405 4660);
PAINT MONO (-3405 4660);
FORCEPROP 1 LAST MATERIAL X7R
J 0
(-4125 4525);
DISPLAY 0.617021 (-4125 4525);
PAINT SKYBLUE (-4125 4525);
FORCEPROP 1 LASTPIN (-3600 4650) $PN 1
J 0
(-3605 4660);
DISPLAY 0.617021 (-3605 4660);
PAINT MONO (-3605 4660);
FORCEPROP 1 LAST TOLERANCE 10%
J 0
(-3500 4575);
DISPLAY 0.617021 (-3500 4575);
PAINT SKYBLUE (-3500 4575);
FORCEPROP 2 LAST SEC 1
R 1
J 0
(-3700 4700);
DISPLAY 0.936170 (-3700 4700);
PAINT MONO (-3700 4700);
DISPLAY INVISIBLE (-3700 4700);
FORCEPROP 2 LAST SEC_TYPE 0402V
R 1
J 0
(-3700 4700);
PAINT MONO (-3700 4700);
DISPLAY INVISIBLE (-3700 4700);
FORCEPROP 2 LAST CDS_SEC 1
R 1
J 0
(-3650 4700);
PAINT ORANGE (-3650 4700);
DISPLAY INVISIBLE (-3650 4700);
FORCEPROP 2 LAST CDS_LIB dev_discrete
R 1
J 0
(-3500 4650);
PAINT ORANGE (-3500 4650);
DISPLAY INVISIBLE (-3500 4650);
FORCEPROP 2 LAST BOM_COST PROC_SIDEBAND
R 1
J 0
(-3500 4650);
PAINT MONO (-3500 4650);
DISPLAY INVISIBLE (-3500 4650);
FORCEPROP 2 LAST ROOM PROC_SIDEBAND
R 1
J 0
(-3250 4700);
DISPLAY 0.978723 (-3250 4700);
PAINT ORANGE (-3250 4700);
DISPLAY INVISIBLE (-3250 4700);
FORCEPROP 2 LAST CDS_LOCATION C25W90
R 1
J 0
(-3600 4700);
DISPLAY 0.617021 (-3600 4700);
PAINT AQUA (-3600 4700);
DISPLAY INVISIBLE (-3600 4700);
FORCEPROP 1 LAST PATH I118
R 1
J 0
(-3650 4700);
DISPLAY 0.978723 (-3650 4700);
PAINT WHITE (-3650 4700);
DISPLAY INVISIBLE (-3650 4700);
FORCEADD GND..1
(-3200 4550);
FORCEPROP 3 LASTPIN (-3200 4600) SIG_NAME GND\g
J 0
(-3190 4610);
DISPLAY 0.659574 (-3190 4610);
PAINT MONO (-3190 4610);
DISPLAY INVISIBLE (-3190 4610);
FORCEPROP 1 LAST SIZE 1B
J 0
(-3166 4541);
DISPLAY 0.872340 (-3166 4541);
PAINT AQUA (-3166 4541);
DISPLAY INVISIBLE (-3166 4541);
FORCEPROP 1 LAST VOLTAGE 0.0V
J 0
(-3261 4523);
DISPLAY 0.340426 (-3261 4523);
PAINT SKYBLUE (-3261 4523);
DISPLAY INVISIBLE (-3261 4523);
FORCEPROP 2 LAST CDS_LIB mstr_symbols
J 0
(-3200 4550);
PAINT MONO (-3200 4550);
DISPLAY INVISIBLE (-3200 4550);
FORCEPROP 1 LAST PATH I119
J 0
(-3125 4550);
DISPLAY 0.872340 (-3125 4550);
PAINT AQUA (-3125 4550);
DISPLAY INVISIBLE (-3125 4550);
FORCEPROP 1 LAST BODY_TYPE PLUMBING
J 0
(-3261 4523);
DISPLAY 0.340426 (-3261 4523);
PAINT GREEN (-3261 4523);
DISPLAY INVISIBLE (-3261 4523);
FORCEPROP 1 LAST HDL_POWER GND
J 0
(-3241 4741);
DISPLAY 0.872340 (-3241 4741);
PAINT GREEN (-3241 4741);
DISPLAY INVISIBLE (-3241 4741);
FORCEADD CAP..1
(-4100 3450);
FORCEPROP 0 LAST GROUP AST2500
J 0
(-4047 3210);
DISPLAY 0.638298 (-4047 3210);
PAINT BROWN (-4047 3210);
DISPLAY BOTH (-4047 3210);
FORCEPROP 1 LAST LOCATION C25W74
J 0
(-4050 3550);
DISPLAY 0.617021 (-4050 3550);
PAINT AQUA (-4050 3550);
FORCEPROP 1 LASTPIN (-4100 3550) $PN 1
J 0
(-4090 3530);
DISPLAY 0.787234 (-4090 3530);
PAINT ORANGE (-4090 3530);
FORCEPROP 1 LAST PACK_TYPE 0402LF
J 0
(-4050 3250);
DISPLAY 0.617021 (-4050 3250);
PAINT SKYBLUE (-4050 3250);
FORCEPROP 1 LASTPIN (-4100 3350) $PN 2
J 0
(-4090 3330);
DISPLAY 0.787234 (-4090 3330);
PAINT ORANGE (-4090 3330);
FORCEPROP 1 LAST MATERIAL COG
J 0
(-4050 3350);
DISPLAY 0.617021 (-4050 3350);
PAINT SKYBLUE (-4050 3350);
FORCEPROP 1 LAST TOLERANCE 5%
J 0
(-4050 3400);
DISPLAY 0.617021 (-4050 3400);
PAINT SKYBLUE (-4050 3400);
FORCEPROP 1 LAST PART_NUMBER A36095-043
J 0
(-4050 3300);
DISPLAY 0.617021 (-4050 3300);
PAINT BLUE (-4050 3300);
FORCEPROP 1 LAST VOLTAGE 50V
J 0
(-4050 3450);
DISPLAY 0.617021 (-4050 3450);
PAINT SKYBLUE (-4050 3450);
FORCEPROP 1 LAST VALUE 12.0PF
J 0
(-4050 3500);
DISPLAY 0.617021 (-4050 3500);
PAINT SKYBLUE (-4050 3500);
FORCEPROP 2 LAST CDS_LOCATION C25W74
J 0
(-4050 3550);
DISPLAY 0.617021 (-4050 3550);
PAINT AQUA (-4050 3550);
DISPLAY INVISIBLE (-4050 3550);
FORCEPROP 1 LAST PATH I12
J 0
(-4050 3600);
DISPLAY 0.978723 (-4050 3600);
PAINT WHITE (-4050 3600);
DISPLAY INVISIBLE (-4050 3600);
FORCEPROP 2 LAST CDS_LIB mstr_discrete
J 0
(-4100 3450);
PAINT ORANGE (-4100 3450);
DISPLAY INVISIBLE (-4100 3450);
FORCEPROP 2 LAST ROOM LBG
J 0
(-4050 3600);
DISPLAY 1.021277 (-4050 3600);
PAINT ORANGE (-4050 3600);
DISPLAY INVISIBLE (-4050 3600);
FORCEPROP 2 LAST BOM_COST LBG_UART
J 0
(-4050 3650);
DISPLAY 1.021277 (-4050 3650);
PAINT ORANGE (-4050 3650);
DISPLAY INVISIBLE (-4050 3650);
FORCEPROP 2 LAST SEC_TYPE 0402LF
J 0
(-4050 3650);
DISPLAY 1.021277 (-4050 3650);
PAINT ORANGE (-4050 3650);
DISPLAY INVISIBLE (-4050 3650);
FORCEPROP 2 LAST SEC 1
J 0
(-4050 3650);
PAINT MONO (-4050 3650);
DISPLAY INVISIBLE (-4050 3650);
FORCEADD RB551V30-GP..1
(-4775 2750);
FORCEPROP 0 LAST GROUP AST2500
J 0
(-4897 2610);
DISPLAY 0.638298 (-4897 2610);
PAINT BROWN (-4897 2610);
DISPLAY BOTH (-4897 2610);
FORCEPROP 2 LASTPIN (-4650 2750) $PN K
J 0
(-4640 2760);
DISPLAY 0.808511 (-4640 2760);
PAINT ORANGE (-4640 2760);
FORCEPROP 1 LAST LOCATION D25W8
J 0
(-4850 2805);
DISPLAY 0.617021 (-4850 2805);
PAINT GREEN (-4850 2805);
FORCEPROP 1 LAST VALUE RB551V30-GP
J 0
(-4850 2670);
DISPLAY 0.617021 (-4850 2670);
PAINT GREEN (-4850 2670);
FORCEPROP 2 LASTPIN (-4900 2750) $PN A
J 2
(-4910 2760);
DISPLAY 0.808511 (-4910 2760);
PAINT ORANGE (-4910 2760);
FORCEPROP 1 LAST PACK_TYPE DISCRET-G
J 0
(-4775 2750);
DISPLAY 0.617021 (-4775 2750);
PAINT GREEN (-4775 2750);
DISPLAY INVISIBLE (-4775 2750);
FORCEPROP 2 LAST SEC 1
J 0
(-4850 2850);
DISPLAY 0.680851 (-4850 2850);
PAINT MONO (-4850 2850);
DISPLAY INVISIBLE (-4850 2850);
FORCEPROP 2 LAST SEC_TYPE DISCRET-G
J 0
(-4850 2850);
DISPLAY 1.021277 (-4850 2850);
PAINT ORANGE (-4850 2850);
DISPLAY INVISIBLE (-4850 2850);
FORCEPROP 1 LAST PART_NUMBER 83.R5003.H8H
J 0
(-4775 2750);
DISPLAY 0.617021 (-4775 2750);
PAINT GREEN (-4775 2750);
DISPLAY INVISIBLE (-4775 2750);
FORCEPROP 2 LAST CDS_LIB w_hdl
J 0
(-4775 2750);
PAINT MONO (-4775 2750);
DISPLAY INVISIBLE (-4775 2750);
FORCEPROP 1 LAST PATH I128
J 0
(-4775 2750);
DISPLAY 0.617021 (-4775 2750);
PAINT GREEN (-4775 2750);
DISPLAY INVISIBLE (-4775 2750);
FORCEPROP 1 LAST CDS_LMAN_SYM_OUTLINE -75,50,75,-50
J 0
(-4775 2750);
DISPLAY 0.468085 (-4775 2750);
PAINT GREEN (-4775 2750);
DISPLAY INVISIBLE (-4775 2750);
FORCEADD DIODEAC_DUAL_ARRAY..7
(-7000 5750);
FORCEPROP 1 LAST LOCATION CR25W1
J 0
(-7300 6100);
DISPLAY 0.617021 (-7300 6100);
PAINT AQUA (-7300 6100);
FORCEPROP 1 LAST MATERIAL IC
J 0
(-7300 6050);
DISPLAY 0.617021 (-7300 6050);
PAINT SKYBLUE (-7300 6050);
FORCEPROP 2 LASTPIN (-6650 5700) $PN 9
J 0
(-6640 5710);
DISPLAY 0.617021 (-6640 5710);
PAINT ORANGE (-6640 5710);
FORCEPROP 2 LASTPIN (-6650 5850) $PN 6
J 0
(-6640 5860);
DISPLAY 0.617021 (-6640 5860);
PAINT ORANGE (-6640 5860);
FORCEPROP 2 LASTPIN (-6650 5600) $PN 3
J 0
(-6640 5610);
DISPLAY 0.617021 (-6640 5610);
PAINT ORANGE (-6640 5610);
FORCEPROP 2 LASTPIN (-6650 5750) $PN 8
J 0
(-6640 5760);
DISPLAY 0.617021 (-6640 5760);
PAINT ORANGE (-6640 5760);
FORCEPROP 2 LASTPIN (-7350 5850) $PN 5
J 2
(-7360 5860);
DISPLAY 0.617021 (-7360 5860);
PAINT ORANGE (-7360 5860);
FORCEPROP 2 LASTPIN (-7350 5800) $PN 4
J 2
(-7360 5810);
DISPLAY 0.617021 (-7360 5810);
PAINT ORANGE (-7360 5810);
FORCEPROP 2 LASTPIN (-7350 5700) $PN 1
J 2
(-7360 5710);
DISPLAY 0.617021 (-7360 5710);
PAINT ORANGE (-7360 5710);
FORCEPROP 2 LASTPIN (-7350 5750) $PN 2
J 2
(-7360 5760);
DISPLAY 0.617021 (-7360 5760);
PAINT ORANGE (-7360 5760);
FORCEPROP 2 LASTPIN (-6650 5800) $PN 7
J 0
(-6640 5810);
DISPLAY 0.617021 (-6640 5810);
PAINT ORANGE (-6640 5810);
FORCEPROP 1 LAST VALUE ESD3V3U4ULC
J 1
(-7025 5925);
DISPLAY 0.617021 (-7025 5925);
PAINT SKYBLUE (-7025 5925);
FORCEPROP 1 LAST PART_NUMBER G18435-001
J 0
(-7300 5450);
DISPLAY 0.617021 (-7300 5450);
PAINT BLUE (-7300 5450);
FORCEPROP 0 LAST GROUP AST2500
J 0
(-7297 5385);
DISPLAY 0.638298 (-7297 5385);
PAINT BROWN (-7297 5385);
DISPLAY BOTH (-7297 5385);
FORCEPROP 2 LAST CDS_LOCATION CR25W1
J 0
(-7300 6100);
DISPLAY 0.617021 (-7300 6100);
PAINT AQUA (-7300 6100);
DISPLAY INVISIBLE (-7300 6100);
FORCEPROP 1 LAST PATH I129
J 0
(-7000 6050);
PAINT GREEN (-7000 6050);
DISPLAY INVISIBLE (-7000 6050);
FORCEPROP 2 LAST CDS_LIB mstr_discrete
J 0
(-7000 5750);
PAINT MONO (-7000 5750);
DISPLAY INVISIBLE (-7000 5750);
FORCEPROP 0 LAST ROOM USB_REAR
J 0
(-7250 6100);
DISPLAY 1.021277 (-7250 6100);
PAINT ORANGE (-7250 6100);
DISPLAY INVISIBLE (-7250 6100);
FORCEPROP 2 LAST SEC 1
J 0
(-7300 6150);
DISPLAY 0.680851 (-7300 6150);
PAINT MONO (-7300 6150);
DISPLAY INVISIBLE (-7300 6150);
FORCEPROP 2 LAST SEC_TYPE SM9
J 0
(-7300 6150);
DISPLAY 1.021277 (-7300 6150);
PAINT ORANGE (-7300 6150);
DISPLAY INVISIBLE (-7300 6150);
FORCEPROP 1 LAST PACK_TYPE SM9
J 0
(-7300 6150);
PAINT SKYBLUE (-7300 6150);
DISPLAY INVISIBLE (-7300 6150);
FORCEPROP 0 LAST BOM_COST MIO_USB
J 0
(-7250 6150);
DISPLAY 1.021277 (-7250 6150);
PAINT ORANGE (-7250 6150);
DISPLAY INVISIBLE (-7250 6150);
FORCEADD OFFPAGE..1
(-5400 3600);
FORCEPROP 2 LAST $XR0 144 
J 0
(-5652 3600);
DISPLAY 0.638298 (-5652 3600);
PAINT MONO (-5652 3600);
FORCEPROP 2 LAST CDS_LIB mstr_standard
J 0
(-5400 3600);
PAINT MONO (-5400 3600);
DISPLAY INVISIBLE (-5400 3600);
FORCEPROP 2 LAST PATH I13
J 0
(-5350 3675);
DISPLAY 1.021277 (-5350 3675);
PAINT ORANGE (-5350 3675);
DISPLAY INVISIBLE (-5350 3675);
FORCEPROP 1 LAST OFFPAGE TRUE
J 0
(-5075 3475);
DISPLAY 0.872340 (-5075 3475);
PAINT GREEN (-5075 3475);
DISPLAY INVISIBLE (-5075 3475);
FORCEPROP 1 LAST COMMENT_BODY TRUE
J 0
(-5275 3500);
DISPLAY 0.872340 (-5275 3500);
PAINT GREEN (-5275 3500);
DISPLAY INVISIBLE (-5275 3500);
FORCEADD GND..1
(-6600 5500);
FORCEPROP 3 LASTPIN (-6600 5550) SIG_NAME GND\g
J 0
(-6590 5560);
DISPLAY 0.659574 (-6590 5560);
PAINT MONO (-6590 5560);
DISPLAY INVISIBLE (-6590 5560);
FORCEPROP 1 LAST PATH I130
J 0
(-6525 5500);
DISPLAY 0.872340 (-6525 5500);
PAINT AQUA (-6525 5500);
DISPLAY INVISIBLE (-6525 5500);
FORCEPROP 1 LAST SIZE 1B
J 0
(-6566 5491);
DISPLAY 0.872340 (-6566 5491);
PAINT AQUA (-6566 5491);
DISPLAY INVISIBLE (-6566 5491);
FORCEPROP 1 LAST VOLTAGE 0.0V
J 0
(-6661 5473);
DISPLAY 0.340426 (-6661 5473);
PAINT SKYBLUE (-6661 5473);
DISPLAY INVISIBLE (-6661 5473);
FORCEPROP 2 LAST CDS_LIB mstr_symbols
J 0
(-6600 5500);
PAINT MONO (-6600 5500);
DISPLAY INVISIBLE (-6600 5500);
FORCEPROP 1 LAST BODY_TYPE PLUMBING
J 0
(-6661 5473);
DISPLAY 0.340426 (-6661 5473);
PAINT GREEN (-6661 5473);
DISPLAY INVISIBLE (-6661 5473);
FORCEPROP 1 LAST HDL_POWER GND
J 0
(-6641 5691);
DISPLAY 0.872340 (-6641 5691);
PAINT GREEN (-6641 5691);
DISPLAY INVISIBLE (-6641 5691);
FORCEADD DIODEAC_DUAL_ARRAY..7
(-4350 5750);
FORCEPROP 2 LASTPIN (-4000 5600) $PN 3
J 0
(-3990 5610);
DISPLAY 0.617021 (-3990 5610);
PAINT ORANGE (-3990 5610);
FORCEPROP 2 LASTPIN (-4000 5700) $PN 9
J 0
(-3990 5710);
DISPLAY 0.617021 (-3990 5710);
PAINT ORANGE (-3990 5710);
FORCEPROP 1 LAST LOCATION CR25W2
J 0
(-4650 6100);
DISPLAY 0.617021 (-4650 6100);
PAINT AQUA (-4650 6100);
FORCEPROP 1 LAST VALUE ESD3V3U4ULC
J 1
(-4375 5925);
DISPLAY 0.617021 (-4375 5925);
PAINT SKYBLUE (-4375 5925);
FORCEPROP 2 LASTPIN (-4700 5800) $PN 4
J 2
(-4710 5810);
DISPLAY 0.617021 (-4710 5810);
PAINT ORANGE (-4710 5810);
FORCEPROP 2 LASTPIN (-4700 5850) $PN 5
J 2
(-4710 5860);
DISPLAY 0.617021 (-4710 5860);
PAINT ORANGE (-4710 5860);
FORCEPROP 1 LAST MATERIAL IC
J 0
(-4650 6050);
DISPLAY 0.617021 (-4650 6050);
PAINT SKYBLUE (-4650 6050);
FORCEPROP 2 LASTPIN (-4000 5800) $PN 7
J 0
(-3990 5810);
DISPLAY 0.617021 (-3990 5810);
PAINT ORANGE (-3990 5810);
FORCEPROP 2 LASTPIN (-4700 5750) $PN 2
J 2
(-4710 5760);
DISPLAY 0.617021 (-4710 5760);
PAINT ORANGE (-4710 5760);
FORCEPROP 2 LASTPIN (-4700 5700) $PN 1
J 2
(-4710 5710);
DISPLAY 0.617021 (-4710 5710);
PAINT ORANGE (-4710 5710);
FORCEPROP 2 LASTPIN (-4000 5850) $PN 6
J 0
(-3990 5860);
DISPLAY 0.617021 (-3990 5860);
PAINT ORANGE (-3990 5860);
FORCEPROP 2 LASTPIN (-4000 5750) $PN 8
J 0
(-3990 5760);
DISPLAY 0.617021 (-3990 5760);
PAINT ORANGE (-3990 5760);
FORCEPROP 0 LAST GROUP AST2500
J 0
(-4647 5385);
DISPLAY 0.638298 (-4647 5385);
PAINT BROWN (-4647 5385);
DISPLAY BOTH (-4647 5385);
FORCEPROP 1 LAST PART_NUMBER G18435-001
J 0
(-4650 5450);
DISPLAY 0.617021 (-4650 5450);
PAINT BLUE (-4650 5450);
FORCEPROP 2 LAST CDS_LOCATION CR25W2
J 0
(-4650 6100);
DISPLAY 0.617021 (-4650 6100);
PAINT AQUA (-4650 6100);
DISPLAY INVISIBLE (-4650 6100);
FORCEPROP 0 LAST BOM_COST MIO_USB
J 0
(-4600 6150);
DISPLAY 1.021277 (-4600 6150);
PAINT ORANGE (-4600 6150);
DISPLAY INVISIBLE (-4600 6150);
FORCEPROP 1 LAST PACK_TYPE SM9
J 0
(-4650 6150);
PAINT SKYBLUE (-4650 6150);
DISPLAY INVISIBLE (-4650 6150);
FORCEPROP 2 LAST SEC_TYPE SM9
J 0
(-4650 6150);
DISPLAY 1.021277 (-4650 6150);
PAINT ORANGE (-4650 6150);
DISPLAY INVISIBLE (-4650 6150);
FORCEPROP 2 LAST SEC 1
J 0
(-4650 6150);
DISPLAY 0.680851 (-4650 6150);
PAINT MONO (-4650 6150);
DISPLAY INVISIBLE (-4650 6150);
FORCEPROP 0 LAST ROOM USB_REAR
J 0
(-4600 6100);
DISPLAY 1.021277 (-4600 6100);
PAINT ORANGE (-4600 6100);
DISPLAY INVISIBLE (-4600 6100);
FORCEPROP 2 LAST CDS_LIB mstr_discrete
J 0
(-4350 5750);
PAINT MONO (-4350 5750);
DISPLAY INVISIBLE (-4350 5750);
FORCEPROP 1 LAST PATH I131
J 0
(-4350 6050);
PAINT GREEN (-4350 6050);
DISPLAY INVISIBLE (-4350 6050);
FORCEADD GND..1
(-3950 5500);
FORCEPROP 3 LASTPIN (-3950 5550) SIG_NAME GND\g
J 0
(-3940 5560);
DISPLAY 0.659574 (-3940 5560);
PAINT MONO (-3940 5560);
DISPLAY INVISIBLE (-3940 5560);
FORCEPROP 2 LAST CDS_LIB mstr_symbols
J 0
(-3950 5500);
PAINT MONO (-3950 5500);
DISPLAY INVISIBLE (-3950 5500);
FORCEPROP 1 LAST VOLTAGE 0.0V
J 0
(-4011 5473);
DISPLAY 0.340426 (-4011 5473);
PAINT SKYBLUE (-4011 5473);
DISPLAY INVISIBLE (-4011 5473);
FORCEPROP 1 LAST SIZE 1B
J 0
(-3916 5491);
DISPLAY 0.872340 (-3916 5491);
PAINT AQUA (-3916 5491);
DISPLAY INVISIBLE (-3916 5491);
FORCEPROP 1 LAST PATH I132
J 0
(-3875 5500);
DISPLAY 0.872340 (-3875 5500);
PAINT AQUA (-3875 5500);
DISPLAY INVISIBLE (-3875 5500);
FORCEPROP 1 LAST BODY_TYPE PLUMBING
J 0
(-4011 5473);
DISPLAY 0.340426 (-4011 5473);
PAINT GREEN (-4011 5473);
DISPLAY INVISIBLE (-4011 5473);
FORCEPROP 1 LAST HDL_POWER GND
J 0
(-3991 5691);
DISPLAY 0.872340 (-3991 5691);
PAINT GREEN (-3991 5691);
DISPLAY INVISIBLE (-3991 5691);
FORCEADD GND..1
(-3200 5100);
FORCEPROP 3 LASTPIN (-3200 5150) SIG_NAME GND\g
J 0
(-3190 5160);
DISPLAY 0.659574 (-3190 5160);
PAINT MONO (-3190 5160);
DISPLAY INVISIBLE (-3190 5160);
FORCEPROP 1 LAST PATH I133
J 0
(-3125 5100);
DISPLAY 0.872340 (-3125 5100);
PAINT AQUA (-3125 5100);
DISPLAY INVISIBLE (-3125 5100);
FORCEPROP 1 LAST SIZE 1B
J 0
(-3166 5091);
DISPLAY 0.872340 (-3166 5091);
PAINT AQUA (-3166 5091);
DISPLAY INVISIBLE (-3166 5091);
FORCEPROP 1 LAST VOLTAGE 0.0V
J 0
(-3261 5073);
DISPLAY 0.340426 (-3261 5073);
PAINT SKYBLUE (-3261 5073);
DISPLAY INVISIBLE (-3261 5073);
FORCEPROP 2 LAST CDS_LIB mstr_symbols
J 0
(-3200 5100);
PAINT MONO (-3200 5100);
DISPLAY INVISIBLE (-3200 5100);
FORCEPROP 1 LAST BODY_TYPE PLUMBING
J 0
(-3261 5073);
DISPLAY 0.340426 (-3261 5073);
PAINT GREEN (-3261 5073);
DISPLAY INVISIBLE (-3261 5073);
FORCEPROP 1 LAST HDL_POWER GND
J 0
(-3241 5291);
DISPLAY 0.872340 (-3241 5291);
PAINT GREEN (-3241 5291);
DISPLAY INVISIBLE (-3241 5291);
FORCEADD CAP_A..1
R 1
(-3500 5200);
FORCEPROP 1 LAST VALUE 0.1UF
J 0
(-3925 5125);
DISPLAY 0.617021 (-3925 5125);
PAINT SKYBLUE (-3925 5125);
FORCEPROP 1 LAST PACK_TYPE 0402V
J 0
(-3650 5075);
DISPLAY 0.617021 (-3650 5075);
PAINT SKYBLUE (-3650 5075);
FORCEPROP 1 LAST VOLTAGE 16V
J 0
(-3650 5125);
DISPLAY 0.617021 (-3650 5125);
PAINT SKYBLUE (-3650 5125);
FORCEPROP 1 LASTPIN (-3600 5200) $PN 1
J 0
(-3605 5210);
DISPLAY 0.617021 (-3605 5210);
PAINT MONO (-3605 5210);
FORCEPROP 1 LAST MATERIAL X7R
J 0
(-4125 5075);
DISPLAY 0.617021 (-4125 5075);
PAINT SKYBLUE (-4125 5075);
FORCEPROP 1 LASTPIN (-3400 5200) $PN 2
J 0
(-3405 5210);
DISPLAY 0.617021 (-3405 5210);
PAINT MONO (-3405 5210);
FORCEPROP 1 LAST LOCATION C25P80
J 0
(-4125 5125);
DISPLAY 0.617021 (-4125 5125);
PAINT AQUA (-4125 5125);
FORCEPROP 1 LAST TOLERANCE 10%
J 0
(-3500 5125);
DISPLAY 0.617021 (-3500 5125);
PAINT SKYBLUE (-3500 5125);
FORCEPROP 1 LAST PART_NUMBER A36096-030
J 0
(-3925 5075);
DISPLAY 0.617021 (-3925 5075);
PAINT BLUE (-3925 5075);
FORCEPROP 0 LAST GROUP AST2500
J 0
(-3485 5078);
DISPLAY 0.638298 (-3485 5078);
PAINT BROWN (-3485 5078);
DISPLAY BOTH (-3485 5078);
FORCEPROP 2 LAST CDS_LOCATION C25P80
R 1
J 0
(-3600 5250);
DISPLAY 0.617021 (-3600 5250);
PAINT AQUA (-3600 5250);
DISPLAY INVISIBLE (-3600 5250);
FORCEPROP 1 LAST PATH I134
R 1
J 0
(-3650 5250);
DISPLAY 0.978723 (-3650 5250);
PAINT WHITE (-3650 5250);
DISPLAY INVISIBLE (-3650 5250);
FORCEPROP 2 LAST SEC 1
R 1
J 0
(-3700 5250);
DISPLAY 0.936170 (-3700 5250);
PAINT MONO (-3700 5250);
DISPLAY INVISIBLE (-3700 5250);
FORCEPROP 2 LAST SEC_TYPE 0402V
R 1
J 0
(-3700 5250);
PAINT MONO (-3700 5250);
DISPLAY INVISIBLE (-3700 5250);
FORCEPROP 2 LAST CDS_SEC 1
R 1
J 0
(-3650 5250);
PAINT ORANGE (-3650 5250);
DISPLAY INVISIBLE (-3650 5250);
FORCEPROP 2 LAST CDS_LIB dev_discrete
R 1
J 0
(-3500 5200);
PAINT ORANGE (-3500 5200);
DISPLAY INVISIBLE (-3500 5200);
FORCEPROP 2 LAST BOM_COST PROC_SIDEBAND
R 1
J 0
(-3500 5200);
PAINT MONO (-3500 5200);
DISPLAY INVISIBLE (-3500 5200);
FORCEPROP 2 LAST ROOM PROC_SIDEBAND
R 1
J 0
(-3250 5250);
DISPLAY 0.978723 (-3250 5250);
PAINT ORANGE (-3250 5250);
DISPLAY INVISIBLE (-3250 5250);
FORCEADD W_VCC_CIRCLE..1
(-3850 5250);
FORCEPROP 3 LASTPIN (-3850 5250) SIG_NAME P5V_VGA_D\g
J 0
(-3840 5260);
DISPLAY 0.659574 (-3840 5260);
PAINT MONO (-3840 5260);
DISPLAY INVISIBLE (-3840 5260);
FORCEPROP 1 LAST HDL_POWER P5V_VGA_D
J 1
(-3829 5325);
DISPLAY 0.872340 (-3829 5325);
PAINT ORANGE (-3829 5325);
FORCEPROP 1 LAST PATH I135
J 0
(-3850 5250);
DISPLAY 0.617021 (-3850 5250);
PAINT GREEN (-3850 5250);
DISPLAY INVISIBLE (-3850 5250);
FORCEPROP 1 LAST CDS_LMAN_SYM_OUTLINE -100,100,100,-100
J 0
(-3850 5250);
DISPLAY 0.468085 (-3850 5250);
PAINT GREEN (-3850 5250);
DISPLAY INVISIBLE (-3850 5250);
FORCEPROP 2 LAST CDS_LIB w_power
J 0
(-3850 5250);
PAINT MONO (-3850 5250);
DISPLAY INVISIBLE (-3850 5250);
FORCEPROP 1 LAST BODY_TYPE PLUMBING
J 0
(-3838 5244);
DISPLAY 0.340426 (-3838 5244);
PAINT GREEN (-3838 5244);
DISPLAY INVISIBLE (-3838 5244);
FORCEADD SMC-CON13-GP..1
(-9225 2725);
FORCEPROP 2 LASTPIN (-9000 3100) $PN PTH1
J 0
(-8990 3110);
DISPLAY 0.808511 (-8990 3110);
PAINT ORANGE (-8990 3110);
FORCEPROP 0 LAST GROUP AST2500
J 0
(-9300 3250);
DISPLAY 1.021277 (-9300 3250);
PAINT BROWN (-9300 3250);
DISPLAY BOTH (-9300 3250);
FORCEPROP 2 LASTPIN (-9000 2350) $PN PTH2
J 0
(-8990 2360);
DISPLAY 0.808511 (-8990 2360);
PAINT ORANGE (-8990 2360);
FORCEPROP 1 LAST VALUE SMC-CON13-GP
J 0
(-9300 2265);
DISPLAY 0.617021 (-9300 2265);
PAINT GREEN (-9300 2265);
FORCEPROP 1 LAST LOCATION J25W1
J 0
(-9300 3160);
DISPLAY 0.617021 (-9300 3160);
PAINT GREEN (-9300 3160);
FORCEPROP 2 LASTPIN (-9000 2450) $PN 12
J 0
(-8990 2460);
DISPLAY 0.808511 (-8990 2460);
PAINT ORANGE (-8990 2460);
FORCEPROP 2 LASTPIN (-9000 2500) $PN 11
J 0
(-8990 2510);
DISPLAY 0.808511 (-8990 2510);
PAINT ORANGE (-8990 2510);
FORCEPROP 2 LASTPIN (-9000 2550) $PN 10
J 0
(-8990 2560);
DISPLAY 0.808511 (-8990 2560);
PAINT ORANGE (-8990 2560);
FORCEPROP 2 LASTPIN (-9000 2600) $PN 9
J 0
(-8990 2610);
DISPLAY 0.808511 (-8990 2610);
PAINT ORANGE (-8990 2610);
FORCEPROP 2 LASTPIN (-9000 2650) $PN 8
J 0
(-8990 2660);
DISPLAY 0.808511 (-8990 2660);
PAINT ORANGE (-8990 2660);
FORCEPROP 2 LASTPIN (-9000 2700) $PN 7
J 0
(-8990 2710);
DISPLAY 0.808511 (-8990 2710);
PAINT ORANGE (-8990 2710);
FORCEPROP 2 LASTPIN (-9000 2750) $PN 6
J 0
(-8990 2760);
DISPLAY 0.808511 (-8990 2760);
PAINT ORANGE (-8990 2760);
FORCEPROP 2 LASTPIN (-9000 2800) $PN 5
J 0
(-8990 2810);
DISPLAY 0.808511 (-8990 2810);
PAINT ORANGE (-8990 2810);
FORCEPROP 2 LASTPIN (-9000 2850) $PN 4
J 0
(-8990 2860);
DISPLAY 0.808511 (-8990 2860);
PAINT ORANGE (-8990 2860);
FORCEPROP 2 LASTPIN (-9000 2900) $PN 3
J 0
(-8990 2910);
DISPLAY 0.808511 (-8990 2910);
PAINT ORANGE (-8990 2910);
FORCEPROP 2 LASTPIN (-9000 2950) $PN 2
J 0
(-8990 2960);
DISPLAY 0.808511 (-8990 2960);
PAINT ORANGE (-8990 2960);
FORCEPROP 2 LASTPIN (-9000 3050) $PN 1
J 0
(-8990 3060);
DISPLAY 0.808511 (-8990 3060);
PAINT ORANGE (-8990 3060);
FORCEPROP 2 LASTPIN (-9000 2400) $PN 13
J 0
(-8990 2410);
DISPLAY 0.808511 (-8990 2410);
PAINT ORANGE (-8990 2410);
FORCEPROP 1 LAST PACK_TYPE CONN-GC2
J 0
(-9225 2725);
DISPLAY 0.617021 (-9225 2725);
PAINT GREEN (-9225 2725);
DISPLAY INVISIBLE (-9225 2725);
FORCEPROP 2 LAST SEC 1
J 0
(-9300 3200);
DISPLAY 0.680851 (-9300 3200);
PAINT MONO (-9300 3200);
DISPLAY INVISIBLE (-9300 3200);
FORCEPROP 2 LAST SEC_TYPE CONN-GC2
J 0
(-9300 3200);
DISPLAY 1.021277 (-9300 3200);
PAINT ORANGE (-9300 3200);
DISPLAY INVISIBLE (-9300 3200);
FORCEPROP 1 LAST CDS_LMAN_SYM_OUTLINE -75,425,75,-425
J 0
(-9225 2725);
DISPLAY 0.468085 (-9225 2725);
PAINT GREEN (-9225 2725);
DISPLAY INVISIBLE (-9225 2725);
FORCEPROP 1 LAST PATH I136
J 0
(-9225 2725);
DISPLAY 0.617021 (-9225 2725);
PAINT GREEN (-9225 2725);
DISPLAY INVISIBLE (-9225 2725);
FORCEPROP 2 LAST CDS_LIB w_hdl
J 0
(-9225 2725);
PAINT MONO (-9225 2725);
DISPLAY INVISIBLE (-9225 2725);
FORCEPROP 1 LAST PART_NUMBER 021.D0181.0113
J 0
(-9225 2725);
DISPLAY 0.617021 (-9225 2725);
PAINT GREEN (-9225 2725);
DISPLAY INVISIBLE (-9225 2725);
FORCEADD GND..1
(-8750 2250);
FORCEPROP 3 LASTPIN (-8750 2300) SIG_NAME GND\g
J 0
(-8740 2310);
DISPLAY 0.659574 (-8740 2310);
PAINT MONO (-8740 2310);
DISPLAY INVISIBLE (-8740 2310);
FORCEPROP 1 LAST PATH I137
J 0
(-8675 2250);
DISPLAY 0.872340 (-8675 2250);
PAINT AQUA (-8675 2250);
DISPLAY INVISIBLE (-8675 2250);
FORCEPROP 1 LAST SIZE 1B
J 0
(-8716 2241);
DISPLAY 0.872340 (-8716 2241);
PAINT AQUA (-8716 2241);
DISPLAY INVISIBLE (-8716 2241);
FORCEPROP 1 LAST VOLTAGE 0.0V
J 0
(-8811 2223);
DISPLAY 0.340426 (-8811 2223);
PAINT SKYBLUE (-8811 2223);
DISPLAY INVISIBLE (-8811 2223);
FORCEPROP 2 LAST CDS_LIB mstr_symbols
J 0
(-8750 2250);
PAINT MONO (-8750 2250);
DISPLAY INVISIBLE (-8750 2250);
FORCEPROP 1 LAST BODY_TYPE PLUMBING
J 0
(-8811 2223);
DISPLAY 0.340426 (-8811 2223);
PAINT GREEN (-8811 2223);
DISPLAY INVISIBLE (-8811 2223);
FORCEPROP 1 LAST HDL_POWER GND
J 0
(-8791 2441);
DISPLAY 0.872340 (-8791 2441);
PAINT GREEN (-8791 2441);
DISPLAY INVISIBLE (-8791 2441);
FORCEADD GND..1
(-8750 3100);
FORCEPROP 3 LASTPIN (-8750 3150) SIG_NAME GND\g
J 0
(-8740 3160);
DISPLAY 0.659574 (-8740 3160);
PAINT MONO (-8740 3160);
DISPLAY INVISIBLE (-8740 3160);
FORCEPROP 1 LAST PATH I138
J 0
(-8675 3100);
DISPLAY 0.872340 (-8675 3100);
PAINT AQUA (-8675 3100);
DISPLAY INVISIBLE (-8675 3100);
FORCEPROP 1 LAST SIZE 1B
J 0
(-8716 3091);
DISPLAY 0.872340 (-8716 3091);
PAINT AQUA (-8716 3091);
DISPLAY INVISIBLE (-8716 3091);
FORCEPROP 1 LAST VOLTAGE 0.0V
J 0
(-8811 3073);
DISPLAY 0.340426 (-8811 3073);
PAINT SKYBLUE (-8811 3073);
DISPLAY INVISIBLE (-8811 3073);
FORCEPROP 2 LAST CDS_LIB mstr_symbols
J 0
(-8750 3100);
PAINT MONO (-8750 3100);
DISPLAY INVISIBLE (-8750 3100);
FORCEPROP 1 LAST BODY_TYPE PLUMBING
J 0
(-8811 3073);
DISPLAY 0.340426 (-8811 3073);
PAINT GREEN (-8811 3073);
DISPLAY INVISIBLE (-8811 3073);
FORCEPROP 1 LAST HDL_POWER GND
J 0
(-8791 3291);
DISPLAY 0.872340 (-8791 3291);
PAINT GREEN (-8791 3291);
DISPLAY INVISIBLE (-8791 3291);
FORCEADD GND..1
R 1
(-8800 2950);
FORCEPROP 3 LASTPIN (-8850 2950) SIG_NAME GND\g
J 0
(-8840 2960);
DISPLAY 0.659574 (-8840 2960);
PAINT MONO (-8840 2960);
DISPLAY INVISIBLE (-8840 2960);
FORCEPROP 1 LAST PATH I139
R 1
J 0
(-8800 3025);
DISPLAY 0.872340 (-8800 3025);
PAINT AQUA (-8800 3025);
DISPLAY INVISIBLE (-8800 3025);
FORCEPROP 2 LAST CDS_LIB mstr_symbols
R 1
J 0
(-8800 2950);
PAINT MONO (-8800 2950);
DISPLAY INVISIBLE (-8800 2950);
FORCEPROP 1 LAST VOLTAGE 0.0V
R 1
J 0
(-8773 2889);
DISPLAY 0.340426 (-8773 2889);
PAINT SKYBLUE (-8773 2889);
DISPLAY INVISIBLE (-8773 2889);
FORCEPROP 1 LAST SIZE 1B
R 1
J 0
(-8791 2984);
DISPLAY 0.872340 (-8791 2984);
PAINT AQUA (-8791 2984);
DISPLAY INVISIBLE (-8791 2984);
FORCEPROP 1 LAST BODY_TYPE PLUMBING
R 1
J 0
(-8773 2889);
DISPLAY 0.340426 (-8773 2889);
PAINT GREEN (-8773 2889);
DISPLAY INVISIBLE (-8773 2889);
FORCEPROP 1 LAST HDL_POWER GND
R 1
J 0
(-8991 2909);
DISPLAY 0.872340 (-8991 2909);
PAINT GREEN (-8991 2909);
DISPLAY INVISIBLE (-8991 2909);
FORCEADD OFFPAGE..1
(-5400 3750);
FORCEPROP 2 LAST $XR0 144 
J 0
(-5652 3750);
DISPLAY 0.638298 (-5652 3750);
PAINT MONO (-5652 3750);
FORCEPROP 2 LAST CDS_LIB mstr_standard
J 0
(-5400 3750);
PAINT MONO (-5400 3750);
DISPLAY INVISIBLE (-5400 3750);
FORCEPROP 2 LAST PATH I14
J 0
(-5350 3825);
DISPLAY 1.021277 (-5350 3825);
PAINT ORANGE (-5350 3825);
DISPLAY INVISIBLE (-5350 3825);
FORCEPROP 1 LAST OFFPAGE TRUE
J 0
(-5075 3625);
DISPLAY 0.872340 (-5075 3625);
PAINT GREEN (-5075 3625);
DISPLAY INVISIBLE (-5075 3625);
FORCEPROP 1 LAST COMMENT_BODY TRUE
J 0
(-5275 3650);
DISPLAY 0.872340 (-5275 3650);
PAINT GREEN (-5275 3650);
DISPLAY INVISIBLE (-5275 3650);
FORCEADD GND..1
R 1
(-8800 2850);
FORCEPROP 3 LASTPIN (-8850 2850) SIG_NAME GND\g
J 0
(-8840 2860);
DISPLAY 0.659574 (-8840 2860);
PAINT MONO (-8840 2860);
DISPLAY INVISIBLE (-8840 2860);
FORCEPROP 1 LAST PATH I140
R 1
J 0
(-8800 2925);
DISPLAY 0.872340 (-8800 2925);
PAINT AQUA (-8800 2925);
DISPLAY INVISIBLE (-8800 2925);
FORCEPROP 2 LAST CDS_LIB mstr_symbols
R 1
J 0
(-8800 2850);
PAINT MONO (-8800 2850);
DISPLAY INVISIBLE (-8800 2850);
FORCEPROP 1 LAST VOLTAGE 0.0V
R 1
J 0
(-8773 2789);
DISPLAY 0.340426 (-8773 2789);
PAINT SKYBLUE (-8773 2789);
DISPLAY INVISIBLE (-8773 2789);
FORCEPROP 1 LAST SIZE 1B
R 1
J 0
(-8791 2884);
DISPLAY 0.872340 (-8791 2884);
PAINT AQUA (-8791 2884);
DISPLAY INVISIBLE (-8791 2884);
FORCEPROP 1 LAST BODY_TYPE PLUMBING
R 1
J 0
(-8773 2789);
DISPLAY 0.340426 (-8773 2789);
PAINT GREEN (-8773 2789);
DISPLAY INVISIBLE (-8773 2789);
FORCEPROP 1 LAST HDL_POWER GND
R 1
J 0
(-8991 2809);
DISPLAY 0.872340 (-8991 2809);
PAINT GREEN (-8991 2809);
DISPLAY INVISIBLE (-8991 2809);
FORCEADD GND..1
R 1
(-8800 2750);
FORCEPROP 3 LASTPIN (-8850 2750) SIG_NAME GND\g
J 0
(-8840 2760);
DISPLAY 0.659574 (-8840 2760);
PAINT MONO (-8840 2760);
DISPLAY INVISIBLE (-8840 2760);
FORCEPROP 1 LAST PATH I141
R 1
J 0
(-8800 2825);
DISPLAY 0.872340 (-8800 2825);
PAINT AQUA (-8800 2825);
DISPLAY INVISIBLE (-8800 2825);
FORCEPROP 2 LAST CDS_LIB mstr_symbols
R 1
J 0
(-8800 2750);
PAINT MONO (-8800 2750);
DISPLAY INVISIBLE (-8800 2750);
FORCEPROP 1 LAST VOLTAGE 0.0V
R 1
J 0
(-8773 2689);
DISPLAY 0.340426 (-8773 2689);
PAINT SKYBLUE (-8773 2689);
DISPLAY INVISIBLE (-8773 2689);
FORCEPROP 1 LAST SIZE 1B
R 1
J 0
(-8791 2784);
DISPLAY 0.872340 (-8791 2784);
PAINT AQUA (-8791 2784);
DISPLAY INVISIBLE (-8791 2784);
FORCEPROP 1 LAST BODY_TYPE PLUMBING
R 1
J 0
(-8773 2689);
DISPLAY 0.340426 (-8773 2689);
PAINT GREEN (-8773 2689);
DISPLAY INVISIBLE (-8773 2689);
FORCEPROP 1 LAST HDL_POWER GND
R 1
J 0
(-8991 2709);
DISPLAY 0.872340 (-8991 2709);
PAINT GREEN (-8991 2709);
DISPLAY INVISIBLE (-8991 2709);
FORCEADD GND..1
R 1
(-8800 2650);
FORCEPROP 3 LASTPIN (-8850 2650) SIG_NAME GND\g
J 0
(-8840 2660);
DISPLAY 0.659574 (-8840 2660);
PAINT MONO (-8840 2660);
DISPLAY INVISIBLE (-8840 2660);
FORCEPROP 1 LAST PATH I142
R 1
J 0
(-8800 2725);
DISPLAY 0.872340 (-8800 2725);
PAINT AQUA (-8800 2725);
DISPLAY INVISIBLE (-8800 2725);
FORCEPROP 2 LAST CDS_LIB mstr_symbols
R 1
J 0
(-8800 2650);
PAINT MONO (-8800 2650);
DISPLAY INVISIBLE (-8800 2650);
FORCEPROP 1 LAST VOLTAGE 0.0V
R 1
J 0
(-8773 2589);
DISPLAY 0.340426 (-8773 2589);
PAINT SKYBLUE (-8773 2589);
DISPLAY INVISIBLE (-8773 2589);
FORCEPROP 1 LAST SIZE 1B
R 1
J 0
(-8791 2684);
DISPLAY 0.872340 (-8791 2684);
PAINT AQUA (-8791 2684);
DISPLAY INVISIBLE (-8791 2684);
FORCEPROP 1 LAST BODY_TYPE PLUMBING
R 1
J 0
(-8773 2589);
DISPLAY 0.340426 (-8773 2589);
PAINT GREEN (-8773 2589);
DISPLAY INVISIBLE (-8773 2589);
FORCEPROP 1 LAST HDL_POWER GND
R 1
J 0
(-8991 2609);
DISPLAY 0.872340 (-8991 2609);
PAINT GREEN (-8991 2609);
DISPLAY INVISIBLE (-8991 2609);
FORCEADD GND..1
R 1
(-8800 2550);
FORCEPROP 3 LASTPIN (-8850 2550) SIG_NAME GND\g
J 0
(-8840 2560);
DISPLAY 0.659574 (-8840 2560);
PAINT MONO (-8840 2560);
DISPLAY INVISIBLE (-8840 2560);
FORCEPROP 1 LAST PATH I144
R 1
J 0
(-8800 2625);
DISPLAY 0.872340 (-8800 2625);
PAINT AQUA (-8800 2625);
DISPLAY INVISIBLE (-8800 2625);
FORCEPROP 2 LAST CDS_LIB mstr_symbols
R 1
J 0
(-8800 2550);
PAINT MONO (-8800 2550);
DISPLAY INVISIBLE (-8800 2550);
FORCEPROP 1 LAST VOLTAGE 0.0V
R 1
J 0
(-8773 2489);
DISPLAY 0.340426 (-8773 2489);
PAINT SKYBLUE (-8773 2489);
DISPLAY INVISIBLE (-8773 2489);
FORCEPROP 1 LAST SIZE 1B
R 1
J 0
(-8791 2584);
DISPLAY 0.872340 (-8791 2584);
PAINT AQUA (-8791 2584);
DISPLAY INVISIBLE (-8791 2584);
FORCEPROP 1 LAST BODY_TYPE PLUMBING
R 1
J 0
(-8773 2489);
DISPLAY 0.340426 (-8773 2489);
PAINT GREEN (-8773 2489);
DISPLAY INVISIBLE (-8773 2489);
FORCEPROP 1 LAST HDL_POWER GND
R 1
J 0
(-8991 2509);
DISPLAY 0.872340 (-8991 2509);
PAINT GREEN (-8991 2509);
DISPLAY INVISIBLE (-8991 2509);
FORCEADD P5V..1
(-5300 2850);
FORCEPROP 3 LASTPIN (-5300 2800) SIG_NAME P5V\g
J 0
(-5290 2810);
DISPLAY 0.659574 (-5290 2810);
PAINT MONO (-5290 2810);
DISPLAY INVISIBLE (-5290 2810);
FORCEPROP 2 LAST CDS_LIB mstr_symbols
J 0
(-5300 2850);
PAINT ORANGE (-5300 2850);
DISPLAY INVISIBLE (-5300 2850);
FORCEPROP 1 LAST SIZE 1B
J 0
(-5255 2872);
DISPLAY 0.340426 (-5255 2872);
PAINT GREEN (-5255 2872);
DISPLAY INVISIBLE (-5255 2872);
FORCEPROP 1 LAST VOLTAGE +5.0V
J 0
(-5225 3000);
DISPLAY 1.021277 (-5225 3000);
PAINT SKYBLUE (-5225 3000);
DISPLAY INVISIBLE (-5225 3000);
FORCEPROP 1 LAST PATH I145
J 0
(-5255 2852);
DISPLAY 0.340426 (-5255 2852);
PAINT GREEN (-5255 2852);
DISPLAY INVISIBLE (-5255 2852);
FORCEPROP 1 LAST BODY_TYPE PLUMBING
J 0
(-5345 2807);
DISPLAY 0.340426 (-5345 2807);
PAINT GREEN (-5345 2807);
DISPLAY INVISIBLE (-5345 2807);
FORCEPROP 1 LAST HDL_POWER P5V
J 0
(-5600 2725);
DISPLAY 0.872340 (-5600 2725);
PAINT ORANGE (-5600 2725);
DISPLAY INVISIBLE (-5600 2725);
FORCEADD OFFPAGE..1
(-5400 3900);
FORCEPROP 2 LAST $XR0 144 
J 0
(-5652 3900);
DISPLAY 0.638298 (-5652 3900);
PAINT MONO (-5652 3900);
FORCEPROP 2 LAST PATH I15
J 0
(-5350 3975);
DISPLAY 1.021277 (-5350 3975);
PAINT ORANGE (-5350 3975);
DISPLAY INVISIBLE (-5350 3975);
FORCEPROP 2 LAST CDS_LIB mstr_standard
J 0
(-5400 3900);
PAINT MONO (-5400 3900);
DISPLAY INVISIBLE (-5400 3900);
FORCEPROP 1 LAST OFFPAGE TRUE
J 0
(-5075 3775);
DISPLAY 0.872340 (-5075 3775);
PAINT GREEN (-5075 3775);
DISPLAY INVISIBLE (-5075 3775);
FORCEPROP 1 LAST COMMENT_BODY TRUE
J 0
(-5275 3800);
DISPLAY 0.872340 (-5275 3800);
PAINT GREEN (-5275 3800);
DISPLAY INVISIBLE (-5275 3800);
FORCEADD CAP..1
(-2350 3450);
FORCEPROP 1 LAST TOLERANCE 5%
J 0
(-2300 3400);
DISPLAY 0.617021 (-2300 3400);
PAINT SKYBLUE (-2300 3400);
FORCEPROP 1 LAST VALUE 12.0PF
J 0
(-2300 3500);
DISPLAY 0.617021 (-2300 3500);
PAINT SKYBLUE (-2300 3500);
FORCEPROP 1 LASTPIN (-2350 3550) $PN 1
J 0
(-2340 3530);
DISPLAY 0.787234 (-2340 3530);
PAINT ORANGE (-2340 3530);
FORCEPROP 1 LAST PACK_TYPE 0402LF
J 0
(-2300 3250);
DISPLAY 0.617021 (-2300 3250);
PAINT SKYBLUE (-2300 3250);
FORCEPROP 1 LASTPIN (-2350 3350) $PN 2
J 0
(-2340 3330);
DISPLAY 0.787234 (-2340 3330);
PAINT ORANGE (-2340 3330);
FORCEPROP 1 LAST MATERIAL COG
J 0
(-2300 3350);
DISPLAY 0.617021 (-2300 3350);
PAINT SKYBLUE (-2300 3350);
FORCEPROP 1 LAST LOCATION C25W77
J 0
(-2300 3550);
DISPLAY 0.617021 (-2300 3550);
PAINT AQUA (-2300 3550);
FORCEPROP 1 LAST PART_NUMBER A36095-043
J 0
(-2300 3300);
DISPLAY 0.617021 (-2300 3300);
PAINT BLUE (-2300 3300);
FORCEPROP 1 LAST VOLTAGE 50V
J 0
(-2300 3450);
DISPLAY 0.617021 (-2300 3450);
PAINT SKYBLUE (-2300 3450);
FORCEPROP 0 LAST GROUP AST2500
J 0
(-2297 3210);
DISPLAY 0.638298 (-2297 3210);
PAINT BROWN (-2297 3210);
DISPLAY BOTH (-2297 3210);
FORCEPROP 2 LAST BOM_COST LBG_UART
J 0
(-2300 3650);
DISPLAY 1.021277 (-2300 3650);
PAINT ORANGE (-2300 3650);
DISPLAY INVISIBLE (-2300 3650);
FORCEPROP 2 LAST ROOM LBG
J 0
(-2300 3600);
DISPLAY 1.021277 (-2300 3600);
PAINT ORANGE (-2300 3600);
DISPLAY INVISIBLE (-2300 3600);
FORCEPROP 1 LAST PATH I16
J 0
(-2300 3600);
DISPLAY 0.978723 (-2300 3600);
PAINT WHITE (-2300 3600);
DISPLAY INVISIBLE (-2300 3600);
FORCEPROP 2 LAST CDS_LIB mstr_discrete
J 0
(-2350 3450);
PAINT MONO (-2350 3450);
DISPLAY INVISIBLE (-2350 3450);
FORCEPROP 2 LAST SEC_TYPE 0402LF
J 0
(-2300 3650);
DISPLAY 1.021277 (-2300 3650);
PAINT ORANGE (-2300 3650);
DISPLAY INVISIBLE (-2300 3650);
FORCEPROP 2 LAST SEC 1
J 0
(-2300 3650);
DISPLAY 0.680851 (-2300 3650);
PAINT MONO (-2300 3650);
DISPLAY INVISIBLE (-2300 3650);
FORCEADD GND..1
(-2350 3200);
FORCEPROP 3 LASTPIN (-2350 3250) SIG_NAME GND\g
J 0
(-2340 3260);
DISPLAY 0.659574 (-2340 3260);
PAINT MONO (-2340 3260);
DISPLAY INVISIBLE (-2340 3260);
FORCEPROP 1 LAST SIZE 1B
J 0
(-2316 3191);
DISPLAY 0.872340 (-2316 3191);
PAINT AQUA (-2316 3191);
DISPLAY INVISIBLE (-2316 3191);
FORCEPROP 1 LAST VOLTAGE 0.0V
J 0
(-2411 3173);
DISPLAY 0.340426 (-2411 3173);
PAINT SKYBLUE (-2411 3173);
DISPLAY INVISIBLE (-2411 3173);
FORCEPROP 1 LAST PATH I17
J 0
(-2275 3200);
DISPLAY 0.872340 (-2275 3200);
PAINT AQUA (-2275 3200);
DISPLAY INVISIBLE (-2275 3200);
FORCEPROP 2 LAST CDS_LIB mstr_symbols
J 0
(-2350 3200);
PAINT MONO (-2350 3200);
DISPLAY INVISIBLE (-2350 3200);
FORCEPROP 1 LAST BODY_TYPE PLUMBING
J 0
(-2411 3173);
DISPLAY 0.340426 (-2411 3173);
PAINT GREEN (-2411 3173);
DISPLAY INVISIBLE (-2411 3173);
FORCEPROP 1 LAST HDL_POWER GND
J 0
(-2391 3391);
DISPLAY 0.872340 (-2391 3391);
PAINT GREEN (-2391 3391);
DISPLAY INVISIBLE (-2391 3391);
FORCEADD CAP..1
(-2700 3450);
FORCEPROP 0 LAST GROUP AST2500
J 0
(-2647 3210);
DISPLAY 0.638298 (-2647 3210);
PAINT BROWN (-2647 3210);
DISPLAY BOTH (-2647 3210);
FORCEPROP 1 LAST VOLTAGE 50V
J 0
(-2650 3450);
DISPLAY 0.617021 (-2650 3450);
PAINT SKYBLUE (-2650 3450);
FORCEPROP 1 LASTPIN (-2700 3550) $PN 1
J 0
(-2690 3530);
DISPLAY 0.787234 (-2690 3530);
PAINT ORANGE (-2690 3530);
FORCEPROP 1 LAST PACK_TYPE 0402LF
J 0
(-2650 3250);
DISPLAY 0.617021 (-2650 3250);
PAINT SKYBLUE (-2650 3250);
FORCEPROP 1 LASTPIN (-2700 3350) $PN 2
J 0
(-2690 3330);
DISPLAY 0.787234 (-2690 3330);
PAINT ORANGE (-2690 3330);
FORCEPROP 1 LAST MATERIAL COG
J 0
(-2650 3350);
DISPLAY 0.617021 (-2650 3350);
PAINT SKYBLUE (-2650 3350);
FORCEPROP 1 LAST TOLERANCE 5%
J 0
(-2650 3400);
DISPLAY 0.617021 (-2650 3400);
PAINT SKYBLUE (-2650 3400);
FORCEPROP 1 LAST LOCATION C25W76
J 0
(-2650 3550);
DISPLAY 0.617021 (-2650 3550);
PAINT AQUA (-2650 3550);
FORCEPROP 1 LAST VALUE 12.0PF
J 0
(-2650 3500);
DISPLAY 0.617021 (-2650 3500);
PAINT SKYBLUE (-2650 3500);
FORCEPROP 1 LAST PART_NUMBER A36095-043
J 0
(-2650 3300);
DISPLAY 0.617021 (-2650 3300);
PAINT BLUE (-2650 3300);
FORCEPROP 2 LAST SEC 1
J 0
(-2650 3650);
DISPLAY 0.680851 (-2650 3650);
PAINT MONO (-2650 3650);
DISPLAY INVISIBLE (-2650 3650);
FORCEPROP 2 LAST SEC_TYPE 0402LF
J 0
(-2650 3650);
DISPLAY 1.021277 (-2650 3650);
PAINT ORANGE (-2650 3650);
DISPLAY INVISIBLE (-2650 3650);
FORCEPROP 2 LAST CDS_LIB mstr_discrete
J 0
(-2700 3450);
PAINT MONO (-2700 3450);
DISPLAY INVISIBLE (-2700 3450);
FORCEPROP 1 LAST PATH I18
J 0
(-2650 3600);
DISPLAY 0.978723 (-2650 3600);
PAINT WHITE (-2650 3600);
DISPLAY INVISIBLE (-2650 3600);
FORCEPROP 2 LAST BOM_COST LBG_UART
J 0
(-2650 3650);
DISPLAY 1.021277 (-2650 3650);
PAINT ORANGE (-2650 3650);
DISPLAY INVISIBLE (-2650 3650);
FORCEPROP 2 LAST ROOM LBG
J 0
(-2650 3600);
DISPLAY 1.021277 (-2650 3600);
PAINT ORANGE (-2650 3600);
DISPLAY INVISIBLE (-2650 3600);
FORCEADD GND..1
(-2700 3200);
FORCEPROP 3 LASTPIN (-2700 3250) SIG_NAME GND\g
J 0
(-2690 3260);
DISPLAY 0.659574 (-2690 3260);
PAINT MONO (-2690 3260);
DISPLAY INVISIBLE (-2690 3260);
FORCEPROP 2 LAST CDS_LIB mstr_symbols
J 0
(-2700 3200);
PAINT MONO (-2700 3200);
DISPLAY INVISIBLE (-2700 3200);
FORCEPROP 1 LAST PATH I19
J 0
(-2625 3200);
DISPLAY 0.872340 (-2625 3200);
PAINT AQUA (-2625 3200);
DISPLAY INVISIBLE (-2625 3200);
FORCEPROP 1 LAST SIZE 1B
J 0
(-2666 3191);
DISPLAY 0.872340 (-2666 3191);
PAINT AQUA (-2666 3191);
DISPLAY INVISIBLE (-2666 3191);
FORCEPROP 1 LAST VOLTAGE 0.0V
J 0
(-2761 3173);
DISPLAY 0.340426 (-2761 3173);
PAINT SKYBLUE (-2761 3173);
DISPLAY INVISIBLE (-2761 3173);
FORCEPROP 1 LAST BODY_TYPE PLUMBING
J 0
(-2761 3173);
DISPLAY 0.340426 (-2761 3173);
PAINT GREEN (-2761 3173);
DISPLAY INVISIBLE (-2761 3173);
FORCEPROP 1 LAST HDL_POWER GND
J 0
(-2741 3391);
DISPLAY 0.872340 (-2741 3391);
PAINT GREEN (-2741 3391);
DISPLAY INVISIBLE (-2741 3391);
FORCEADD GND..1
(-3050 3200);
FORCEPROP 3 LASTPIN (-3050 3250) SIG_NAME GND\g
J 0
(-3040 3260);
DISPLAY 0.659574 (-3040 3260);
PAINT MONO (-3040 3260);
DISPLAY INVISIBLE (-3040 3260);
FORCEPROP 2 LAST CDS_LIB mstr_symbols
J 0
(-3050 3200);
PAINT MONO (-3050 3200);
DISPLAY INVISIBLE (-3050 3200);
FORCEPROP 1 LAST PATH I20
J 0
(-2975 3200);
DISPLAY 0.872340 (-2975 3200);
PAINT AQUA (-2975 3200);
DISPLAY INVISIBLE (-2975 3200);
FORCEPROP 1 LAST SIZE 1B
J 0
(-3016 3191);
DISPLAY 0.872340 (-3016 3191);
PAINT AQUA (-3016 3191);
DISPLAY INVISIBLE (-3016 3191);
FORCEPROP 1 LAST VOLTAGE 0.0V
J 0
(-3111 3173);
DISPLAY 0.340426 (-3111 3173);
PAINT SKYBLUE (-3111 3173);
DISPLAY INVISIBLE (-3111 3173);
FORCEPROP 1 LAST BODY_TYPE PLUMBING
J 0
(-3111 3173);
DISPLAY 0.340426 (-3111 3173);
PAINT GREEN (-3111 3173);
DISPLAY INVISIBLE (-3111 3173);
FORCEPROP 1 LAST HDL_POWER GND
J 0
(-3091 3391);
DISPLAY 0.872340 (-3091 3391);
PAINT GREEN (-3091 3391);
DISPLAY INVISIBLE (-3091 3391);
FORCEADD CAP..1
(-3050 3450);
FORCEPROP 1 LASTPIN (-3050 3550) $PN 1
J 0
(-3040 3530);
DISPLAY 0.787234 (-3040 3530);
PAINT ORANGE (-3040 3530);
FORCEPROP 1 LAST VALUE 12.0PF
J 0
(-3000 3500);
DISPLAY 0.617021 (-3000 3500);
PAINT SKYBLUE (-3000 3500);
FORCEPROP 1 LAST PACK_TYPE 0402LF
J 0
(-3000 3250);
DISPLAY 0.617021 (-3000 3250);
PAINT SKYBLUE (-3000 3250);
FORCEPROP 1 LAST VOLTAGE 50V
J 0
(-3000 3450);
DISPLAY 0.617021 (-3000 3450);
PAINT SKYBLUE (-3000 3450);
FORCEPROP 1 LAST MATERIAL COG
J 0
(-3000 3350);
DISPLAY 0.617021 (-3000 3350);
PAINT SKYBLUE (-3000 3350);
FORCEPROP 1 LAST TOLERANCE 5%
J 0
(-3000 3400);
DISPLAY 0.617021 (-3000 3400);
PAINT SKYBLUE (-3000 3400);
FORCEPROP 1 LAST LOCATION C25W75
J 0
(-3000 3550);
DISPLAY 0.617021 (-3000 3550);
PAINT AQUA (-3000 3550);
FORCEPROP 1 LAST PART_NUMBER A36095-043
J 0
(-3000 3300);
DISPLAY 0.617021 (-3000 3300);
PAINT BLUE (-3000 3300);
FORCEPROP 1 LASTPIN (-3050 3350) $PN 2
J 0
(-3040 3330);
DISPLAY 0.787234 (-3040 3330);
PAINT ORANGE (-3040 3330);
FORCEPROP 0 LAST GROUP AST2500
J 0
(-2997 3210);
DISPLAY 0.638298 (-2997 3210);
PAINT BROWN (-2997 3210);
DISPLAY BOTH (-2997 3210);
FORCEPROP 2 LAST SEC 1
J 0
(-3000 3650);
DISPLAY 0.680851 (-3000 3650);
PAINT MONO (-3000 3650);
DISPLAY INVISIBLE (-3000 3650);
FORCEPROP 2 LAST SEC_TYPE 0402LF
J 0
(-3000 3650);
DISPLAY 1.021277 (-3000 3650);
PAINT ORANGE (-3000 3650);
DISPLAY INVISIBLE (-3000 3650);
FORCEPROP 2 LAST CDS_LIB mstr_discrete
J 0
(-3050 3450);
PAINT MONO (-3050 3450);
DISPLAY INVISIBLE (-3050 3450);
FORCEPROP 1 LAST PATH I21
J 0
(-3000 3600);
DISPLAY 0.978723 (-3000 3600);
PAINT WHITE (-3000 3600);
DISPLAY INVISIBLE (-3000 3600);
FORCEPROP 2 LAST BOM_COST LBG_UART
J 0
(-3000 3650);
DISPLAY 1.021277 (-3000 3650);
PAINT ORANGE (-3000 3650);
DISPLAY INVISIBLE (-3000 3650);
FORCEPROP 2 LAST ROOM LBG
J 0
(-3000 3600);
DISPLAY 1.021277 (-3000 3600);
PAINT ORANGE (-3000 3600);
DISPLAY INVISIBLE (-3000 3600);
FORCEADD RES..2
R 2
(-6350 2550);
FORCEPROP 0 LAST GROUP AST2500
J 0
(-6597 2310);
DISPLAY 0.638298 (-6597 2310);
PAINT BROWN (-6597 2310);
DISPLAY BOTH (-6597 2310);
FORCEPROP 1 LAST LOCATION R25W128
J 2
(-6395 2675);
DISPLAY 0.617021 (-6395 2675);
PAINT AQUA (-6395 2675);
FORCEPROP 1 LAST VALUE 150.0
J 2
(-6395 2625);
DISPLAY 0.617021 (-6395 2625);
PAINT SKYBLUE (-6395 2625);
FORCEPROP 1 LAST TOLERANCE 1%
J 2
(-6395 2575);
DISPLAY 0.617021 (-6395 2575);
PAINT SKYBLUE (-6395 2575);
FORCEPROP 1 LAST WATTAGE 1/16W
J 2
(-6390 2525);
DISPLAY 0.617021 (-6390 2525);
PAINT SKYBLUE (-6390 2525);
FORCEPROP 1 LAST MATERIAL CHIP
J 2
(-6390 2475);
DISPLAY 0.617021 (-6390 2475);
PAINT SKYBLUE (-6390 2475);
FORCEPROP 1 LAST PART_NUMBER G21796-009
J 2
(-6390 2425);
DISPLAY 0.617021 (-6390 2425);
PAINT BLUE (-6390 2425);
FORCEPROP 1 LAST PACK_TYPE 0402
J 2
(-6390 2375);
DISPLAY 0.617021 (-6390 2375);
PAINT SKYBLUE (-6390 2375);
FORCEPROP 1 LASTPIN (-6350 2650) $PN 1
J 2
(-6355 2612);
DISPLAY 0.787234 (-6355 2612);
PAINT ORANGE (-6355 2612);
DISPLAY INVISIBLE (-6355 2612);
FORCEPROP 1 LASTPIN (-6350 2450) $PN 2
J 2
(-6355 2460);
DISPLAY 0.787234 (-6355 2460);
PAINT ORANGE (-6355 2460);
DISPLAY INVISIBLE (-6355 2460);
FORCEPROP 2 LAST CDS_LIB mstr_discrete
J 0
(-6350 2550);
PAINT MONO (-6350 2550);
DISPLAY INVISIBLE (-6350 2550);
FORCEPROP 1 LAST PATH I22
J 2
(-6400 2725);
DISPLAY 0.978723 (-6400 2725);
PAINT WHITE (-6400 2725);
DISPLAY INVISIBLE (-6400 2725);
FORCEPROP 2 LAST BOM_COST PROC_SIDEBAND
J 2
(-6350 2550);
PAINT MONO (-6350 2550);
DISPLAY INVISIBLE (-6350 2550);
FORCEPROP 2 LAST ROOM PROC_SIDEBAND
J 2
(-6375 2325);
PAINT ORANGE (-6375 2325);
DISPLAY INVISIBLE (-6375 2325);
FORCEADD GND..1
(-6350 2300);
FORCEPROP 3 LASTPIN (-6350 2350) SIG_NAME GND\g
J 0
(-6340 2360);
DISPLAY 0.659574 (-6340 2360);
PAINT MONO (-6340 2360);
DISPLAY INVISIBLE (-6340 2360);
FORCEPROP 2 LAST CDS_LIB mstr_symbols
J 0
(-6350 2300);
PAINT MONO (-6350 2300);
DISPLAY INVISIBLE (-6350 2300);
FORCEPROP 1 LAST PATH I23
J 0
(-6275 2300);
DISPLAY 0.872340 (-6275 2300);
PAINT AQUA (-6275 2300);
DISPLAY INVISIBLE (-6275 2300);
FORCEPROP 1 LAST SIZE 1B
J 0
(-6316 2291);
DISPLAY 0.872340 (-6316 2291);
PAINT AQUA (-6316 2291);
DISPLAY INVISIBLE (-6316 2291);
FORCEPROP 1 LAST VOLTAGE 0.0V
J 0
(-6411 2273);
DISPLAY 0.340426 (-6411 2273);
PAINT SKYBLUE (-6411 2273);
DISPLAY INVISIBLE (-6411 2273);
FORCEPROP 1 LAST BODY_TYPE PLUMBING
J 0
(-6411 2273);
DISPLAY 0.340426 (-6411 2273);
PAINT GREEN (-6411 2273);
DISPLAY INVISIBLE (-6411 2273);
FORCEPROP 1 LAST HDL_POWER GND
J 0
(-6391 2491);
DISPLAY 0.872340 (-6391 2491);
PAINT GREEN (-6391 2491);
DISPLAY INVISIBLE (-6391 2491);
FORCEADD RES..2
R 2
(-6700 2550);
FORCEPROP 0 LAST GROUP AST2500
J 0
(-6947 2260);
DISPLAY 0.638298 (-6947 2260);
PAINT BROWN (-6947 2260);
DISPLAY BOTH (-6947 2260);
FORCEPROP 1 LAST VALUE 150.0
J 2
(-6745 2625);
DISPLAY 0.617021 (-6745 2625);
PAINT SKYBLUE (-6745 2625);
FORCEPROP 1 LAST PART_NUMBER G21796-009
J 2
(-6740 2425);
DISPLAY 0.617021 (-6740 2425);
PAINT BLUE (-6740 2425);
FORCEPROP 1 LAST WATTAGE 1/16W
J 2
(-6740 2525);
DISPLAY 0.617021 (-6740 2525);
PAINT SKYBLUE (-6740 2525);
FORCEPROP 1 LAST LOCATION R25W127
J 2
(-6745 2675);
DISPLAY 0.617021 (-6745 2675);
PAINT AQUA (-6745 2675);
FORCEPROP 1 LAST TOLERANCE 1%
J 2
(-6745 2575);
DISPLAY 0.617021 (-6745 2575);
PAINT SKYBLUE (-6745 2575);
FORCEPROP 1 LAST PACK_TYPE 0402
J 2
(-6740 2375);
DISPLAY 0.617021 (-6740 2375);
PAINT SKYBLUE (-6740 2375);
FORCEPROP 1 LAST MATERIAL CHIP
J 2
(-6740 2475);
DISPLAY 0.617021 (-6740 2475);
PAINT SKYBLUE (-6740 2475);
FORCEPROP 1 LASTPIN (-6700 2650) $PN 1
J 2
(-6705 2612);
DISPLAY 0.787234 (-6705 2612);
PAINT ORANGE (-6705 2612);
DISPLAY INVISIBLE (-6705 2612);
FORCEPROP 1 LASTPIN (-6700 2450) $PN 2
J 2
(-6705 2460);
DISPLAY 0.787234 (-6705 2460);
PAINT ORANGE (-6705 2460);
DISPLAY INVISIBLE (-6705 2460);
FORCEPROP 2 LAST CDS_LIB mstr_discrete
J 0
(-6700 2550);
PAINT MONO (-6700 2550);
DISPLAY INVISIBLE (-6700 2550);
FORCEPROP 1 LAST PATH I24
J 2
(-6750 2725);
DISPLAY 0.978723 (-6750 2725);
PAINT WHITE (-6750 2725);
DISPLAY INVISIBLE (-6750 2725);
FORCEPROP 2 LAST BOM_COST PROC_SIDEBAND
J 2
(-6700 2550);
PAINT MONO (-6700 2550);
DISPLAY INVISIBLE (-6700 2550);
FORCEPROP 2 LAST ROOM PROC_SIDEBAND
J 2
(-6725 2325);
PAINT ORANGE (-6725 2325);
DISPLAY INVISIBLE (-6725 2325);
FORCEADD GND..1
(-6700 2300);
FORCEPROP 3 LASTPIN (-6700 2350) SIG_NAME GND\g
J 0
(-6690 2360);
DISPLAY 0.659574 (-6690 2360);
PAINT MONO (-6690 2360);
DISPLAY INVISIBLE (-6690 2360);
FORCEPROP 2 LAST CDS_LIB mstr_symbols
J 0
(-6700 2300);
PAINT MONO (-6700 2300);
DISPLAY INVISIBLE (-6700 2300);
FORCEPROP 1 LAST PATH I25
J 0
(-6625 2300);
DISPLAY 0.872340 (-6625 2300);
PAINT AQUA (-6625 2300);
DISPLAY INVISIBLE (-6625 2300);
FORCEPROP 1 LAST SIZE 1B
J 0
(-6666 2291);
DISPLAY 0.872340 (-6666 2291);
PAINT AQUA (-6666 2291);
DISPLAY INVISIBLE (-6666 2291);
FORCEPROP 1 LAST VOLTAGE 0.0V
J 0
(-6761 2273);
DISPLAY 0.340426 (-6761 2273);
PAINT SKYBLUE (-6761 2273);
DISPLAY INVISIBLE (-6761 2273);
FORCEPROP 1 LAST BODY_TYPE PLUMBING
J 0
(-6761 2273);
DISPLAY 0.340426 (-6761 2273);
PAINT GREEN (-6761 2273);
DISPLAY INVISIBLE (-6761 2273);
FORCEPROP 1 LAST HDL_POWER GND
J 0
(-6741 2491);
DISPLAY 0.872340 (-6741 2491);
PAINT GREEN (-6741 2491);
DISPLAY INVISIBLE (-6741 2491);
FORCEADD RES..2
R 2
(-7050 2550);
FORCEPROP 0 LAST GROUP AST2500
J 0
(-7297 2310);
DISPLAY 0.638298 (-7297 2310);
PAINT BROWN (-7297 2310);
DISPLAY BOTH (-7297 2310);
FORCEPROP 1 LAST TOLERANCE 1%
J 2
(-7095 2575);
DISPLAY 0.617021 (-7095 2575);
PAINT SKYBLUE (-7095 2575);
FORCEPROP 1 LAST VALUE 150.0
J 2
(-7095 2625);
DISPLAY 0.617021 (-7095 2625);
PAINT SKYBLUE (-7095 2625);
FORCEPROP 1 LAST PART_NUMBER G21796-009
J 2
(-7090 2425);
DISPLAY 0.617021 (-7090 2425);
PAINT BLUE (-7090 2425);
FORCEPROP 1 LAST PACK_TYPE 0402
J 2
(-7090 2375);
DISPLAY 0.617021 (-7090 2375);
PAINT SKYBLUE (-7090 2375);
FORCEPROP 1 LAST MATERIAL CHIP
J 2
(-7090 2475);
DISPLAY 0.617021 (-7090 2475);
PAINT SKYBLUE (-7090 2475);
FORCEPROP 1 LAST WATTAGE 1/16W
J 2
(-7090 2525);
DISPLAY 0.617021 (-7090 2525);
PAINT SKYBLUE (-7090 2525);
FORCEPROP 1 LAST LOCATION R25W126
J 2
(-7095 2675);
DISPLAY 0.617021 (-7095 2675);
PAINT AQUA (-7095 2675);
FORCEPROP 1 LASTPIN (-7050 2650) $PN 1
J 2
(-7055 2612);
DISPLAY 0.787234 (-7055 2612);
PAINT ORANGE (-7055 2612);
DISPLAY INVISIBLE (-7055 2612);
FORCEPROP 1 LASTPIN (-7050 2450) $PN 2
J 2
(-7055 2460);
DISPLAY 0.787234 (-7055 2460);
PAINT ORANGE (-7055 2460);
DISPLAY INVISIBLE (-7055 2460);
FORCEPROP 2 LAST CDS_LIB mstr_discrete
J 0
(-7050 2550);
PAINT MONO (-7050 2550);
DISPLAY INVISIBLE (-7050 2550);
FORCEPROP 1 LAST PATH I26
J 2
(-7100 2725);
DISPLAY 0.978723 (-7100 2725);
PAINT WHITE (-7100 2725);
DISPLAY INVISIBLE (-7100 2725);
FORCEPROP 2 LAST BOM_COST PROC_SIDEBAND
J 2
(-7050 2550);
PAINT MONO (-7050 2550);
DISPLAY INVISIBLE (-7050 2550);
FORCEPROP 2 LAST ROOM PROC_SIDEBAND
J 2
(-7075 2325);
PAINT ORANGE (-7075 2325);
DISPLAY INVISIBLE (-7075 2325);
FORCEADD GND..1
(-7050 2300);
FORCEPROP 3 LASTPIN (-7050 2350) SIG_NAME GND\g
J 0
(-7040 2360);
DISPLAY 0.659574 (-7040 2360);
PAINT MONO (-7040 2360);
DISPLAY INVISIBLE (-7040 2360);
FORCEPROP 2 LAST CDS_LIB mstr_symbols
J 0
(-7050 2300);
PAINT MONO (-7050 2300);
DISPLAY INVISIBLE (-7050 2300);
FORCEPROP 1 LAST PATH I27
J 0
(-6975 2300);
DISPLAY 0.872340 (-6975 2300);
PAINT AQUA (-6975 2300);
DISPLAY INVISIBLE (-6975 2300);
FORCEPROP 1 LAST SIZE 1B
J 0
(-7016 2291);
DISPLAY 0.872340 (-7016 2291);
PAINT AQUA (-7016 2291);
DISPLAY INVISIBLE (-7016 2291);
FORCEPROP 1 LAST VOLTAGE 0.0V
J 0
(-7111 2273);
DISPLAY 0.340426 (-7111 2273);
PAINT SKYBLUE (-7111 2273);
DISPLAY INVISIBLE (-7111 2273);
FORCEPROP 1 LAST BODY_TYPE PLUMBING
J 0
(-7111 2273);
DISPLAY 0.340426 (-7111 2273);
PAINT GREEN (-7111 2273);
DISPLAY INVISIBLE (-7111 2273);
FORCEPROP 1 LAST HDL_POWER GND
J 0
(-7091 2491);
DISPLAY 0.872340 (-7091 2491);
PAINT GREEN (-7091 2491);
DISPLAY INVISIBLE (-7091 2491);
FORCEADD P3V3..1
(-8200 5550);
FORCEPROP 3 LASTPIN (-8200 5500) SIG_NAME P3V3\g
J 0
(-8190 5510);
DISPLAY 0.659574 (-8190 5510);
PAINT MONO (-8190 5510);
DISPLAY INVISIBLE (-8190 5510);
FORCEPROP 1 LAST PATH I29
J 0
(-8155 5552);
DISPLAY 0.340426 (-8155 5552);
PAINT GREEN (-8155 5552);
DISPLAY INVISIBLE (-8155 5552);
FORCEPROP 1 LAST VOLTAGE 3.3V
J 0
(-8245 5507);
DISPLAY 0.340426 (-8245 5507);
PAINT SKYBLUE (-8245 5507);
DISPLAY INVISIBLE (-8245 5507);
FORCEPROP 1 LAST SIZE 1B
J 0
(-8155 5572);
DISPLAY 0.340426 (-8155 5572);
PAINT GREEN (-8155 5572);
DISPLAY INVISIBLE (-8155 5572);
FORCEPROP 2 LAST CDS_LIB mstr_symbols
J 0
(-8200 5550);
PAINT MONO (-8200 5550);
DISPLAY INVISIBLE (-8200 5550);
FORCEPROP 1 LAST BODY_TYPE PLUMBING
J 0
(-8245 5507);
DISPLAY 0.340426 (-8245 5507);
PAINT GREEN (-8245 5507);
DISPLAY INVISIBLE (-8245 5507);
FORCEPROP 1 LAST HDL_POWER P3V3
J 0
(-8525 5425);
DISPLAY 0.872340 (-8525 5425);
PAINT ORANGE (-8525 5425);
DISPLAY INVISIBLE (-8525 5425);
FORCEADD RES..2
(-8200 5300);
FORCEPROP 1 LAST VALUE 4.75K
J 0
(-8155 5400);
DISPLAY 0.617021 (-8155 5400);
PAINT SKYBLUE (-8155 5400);
FORCEPROP 1 LAST TOLERANCE 1%
J 0
(-8155 5350);
DISPLAY 0.617021 (-8155 5350);
PAINT SKYBLUE (-8155 5350);
FORCEPROP 1 LAST WATTAGE 1/16W
J 0
(-8160 5300);
DISPLAY 0.617021 (-8160 5300);
PAINT SKYBLUE (-8160 5300);
FORCEPROP 1 LAST MATERIAL CHIP
J 0
(-8160 5250);
DISPLAY 0.617021 (-8160 5250);
PAINT SKYBLUE (-8160 5250);
FORCEPROP 1 LAST PART_NUMBER G21796-072
J 0
(-8160 5200);
DISPLAY 0.617021 (-8160 5200);
PAINT BLUE (-8160 5200);
FORCEPROP 1 LAST PACK_TYPE 0402
J 0
(-8160 5150);
DISPLAY 0.617021 (-8160 5150);
PAINT SKYBLUE (-8160 5150);
FORCEPROP 1 LASTPIN (-8200 5200) $PN 2
J 0
(-8195 5210);
DISPLAY 0.617021 (-8195 5210);
PAINT ORANGE (-8195 5210);
FORCEPROP 1 LASTPIN (-8200 5400) $PN 1
J 0
(-8195 5412);
DISPLAY 0.617021 (-8195 5412);
PAINT ORANGE (-8195 5412);
FORCEPROP 1 LAST LOCATION R25W131
J 0
(-8155 5450);
DISPLAY 0.617021 (-8155 5450);
PAINT AQUA (-8155 5450);
FORCEPROP 0 LAST GROUP AST2500
J 0
(-8175 5100);
DISPLAY 0.638298 (-8175 5100);
PAINT BROWN (-8175 5100);
DISPLAY BOTH (-8175 5100);
FORCEPROP 1 LAST PATH I30
J 0
(-8150 5475);
DISPLAY 0.978723 (-8150 5475);
PAINT WHITE (-8150 5475);
DISPLAY INVISIBLE (-8150 5475);
FORCEPROP 0 LAST CDS_SEC 1
J 0
(-8150 5475);
PAINT MONO (-8150 5475);
DISPLAY INVISIBLE (-8150 5475);
FORCEPROP 2 LAST CDS_LIB mstr_discrete
J 0
(-8200 5300);
PAINT ORANGE (-8200 5300);
DISPLAY INVISIBLE (-8200 5300);
FORCEPROP 0 LAST ROOM CPU_FANS
J 0
(-8150 5525);
DISPLAY 1.021277 (-8150 5525);
PAINT ORANGE (-8150 5525);
DISPLAY INVISIBLE (-8150 5525);
FORCEPROP 2 LAST SEC 1
J 0
(-8150 5525);
DISPLAY 0.680851 (-8150 5525);
PAINT MONO (-8150 5525);
DISPLAY INVISIBLE (-8150 5525);
FORCEPROP 2 LAST SEC_TYPE 0402
J 0
(-8150 5525);
DISPLAY 1.021277 (-8150 5525);
PAINT ORANGE (-8150 5525);
DISPLAY INVISIBLE (-8150 5525);
FORCEPROP 0 LAST BOM_COST SM_THERM
J 0
(-8150 5625);
DISPLAY 1.021277 (-8150 5625);
PAINT ORANGE (-8150 5625);
DISPLAY INVISIBLE (-8150 5625);
FORCEPROP 2 LAST CDS_LOCATION R25W131
J 0
(-8155 5425);
DISPLAY 0.617021 (-8155 5425);
PAINT AQUA (-8155 5425);
DISPLAY INVISIBLE (-8155 5425);
FORCEADD RES..2
(-7750 4950);
FORCEPROP 1 LAST PART_NUMBER G21796-072
J 0
(-7710 4850);
DISPLAY 0.617021 (-7710 4850);
PAINT BLUE (-7710 4850);
FORCEPROP 1 LAST WATTAGE 1/16W
J 0
(-7710 4950);
DISPLAY 0.617021 (-7710 4950);
PAINT SKYBLUE (-7710 4950);
FORCEPROP 1 LAST MATERIAL CHIP
J 0
(-7710 4900);
DISPLAY 0.617021 (-7710 4900);
PAINT SKYBLUE (-7710 4900);
FORCEPROP 1 LAST VALUE 4.75K
J 0
(-7705 5050);
DISPLAY 0.617021 (-7705 5050);
PAINT SKYBLUE (-7705 5050);
FORCEPROP 1 LAST PACK_TYPE 0402
J 0
(-7710 4800);
DISPLAY 0.617021 (-7710 4800);
PAINT SKYBLUE (-7710 4800);
FORCEPROP 1 LASTPIN (-7750 5050) $PN 1
J 0
(-7745 5012);
DISPLAY 0.787234 (-7745 5012);
PAINT ORANGE (-7745 5012);
FORCEPROP 1 LASTPIN (-7750 4850) $PN 2
J 0
(-7745 4860);
DISPLAY 0.787234 (-7745 4860);
PAINT ORANGE (-7745 4860);
FORCEPROP 1 LAST TOLERANCE 1%
J 0
(-7705 5000);
DISPLAY 0.617021 (-7705 5000);
PAINT SKYBLUE (-7705 5000);
FORCEPROP 0 LAST GROUP AST2500
J 0
(-7575 5000);
DISPLAY 0.638298 (-7575 5000);
PAINT BROWN (-7575 5000);
DISPLAY BOTH (-7575 5000);
FORCEPROP 1 LAST LOCATION R25W132
J 0
(-7705 5100);
DISPLAY 0.617021 (-7705 5100);
PAINT AQUA (-7705 5100);
FORCEPROP 1 LAST PATH I31
J 0
(-7700 5125);
DISPLAY 0.978723 (-7700 5125);
PAINT WHITE (-7700 5125);
DISPLAY INVISIBLE (-7700 5125);
FORCEPROP 2 LAST CDS_LIB mstr_discrete
J 0
(-7750 4950);
PAINT MONO (-7750 4950);
DISPLAY INVISIBLE (-7750 4950);
FORCEPROP 0 LAST ROOM CPU_FANS
J 0
(-7700 5175);
DISPLAY 1.021277 (-7700 5175);
PAINT ORANGE (-7700 5175);
DISPLAY INVISIBLE (-7700 5175);
FORCEPROP 0 LAST BOM_COST SM_THERM
J 0
(-7700 5275);
DISPLAY 1.021277 (-7700 5275);
PAINT ORANGE (-7700 5275);
DISPLAY INVISIBLE (-7700 5275);
FORCEPROP 2 LAST SEC 1
J 0
(-7700 5175);
DISPLAY 0.680851 (-7700 5175);
PAINT MONO (-7700 5175);
DISPLAY INVISIBLE (-7700 5175);
FORCEPROP 2 LAST SEC_TYPE 0402
J 0
(-7700 5175);
DISPLAY 1.021277 (-7700 5175);
PAINT ORANGE (-7700 5175);
DISPLAY INVISIBLE (-7700 5175);
FORCEADD W_VCC_CIRCLE..1
(-7750 5150);
FORCEPROP 3 LASTPIN (-7750 5150) SIG_NAME P5V_VGA_D\g
J 0
(-7740 5160);
DISPLAY 0.659574 (-7740 5160);
PAINT MONO (-7740 5160);
DISPLAY INVISIBLE (-7740 5160);
FORCEPROP 1 LAST HDL_POWER P5V_VGA_D
J 1
(-7729 5225);
DISPLAY 0.872340 (-7729 5225);
PAINT ORANGE (-7729 5225);
FORCEPROP 1 LAST CDS_LMAN_SYM_OUTLINE -100,100,100,-100
J 0
(-7750 5150);
DISPLAY 0.468085 (-7750 5150);
PAINT GREEN (-7750 5150);
DISPLAY INVISIBLE (-7750 5150);
FORCEPROP 2 LAST CDS_LIB w_power
J 0
(-7750 5150);
PAINT MONO (-7750 5150);
DISPLAY INVISIBLE (-7750 5150);
FORCEPROP 1 LAST PATH I32
J 0
(-7750 5150);
DISPLAY 0.617021 (-7750 5150);
PAINT GREEN (-7750 5150);
DISPLAY INVISIBLE (-7750 5150);
FORCEPROP 1 LAST BODY_TYPE PLUMBING
J 0
(-7738 5144);
DISPLAY 0.340426 (-7738 5144);
PAINT GREEN (-7738 5144);
DISPLAY INVISIBLE (-7738 5144);
FORCEADD OFFPAGE..4
R 2
(-9100 4750);
FORCEPROP 2 LAST $XR0 146 
J 0
(-9352 4750);
DISPLAY 0.638298 (-9352 4750);
PAINT MONO (-9352 4750);
FORCEPROP 2 LAST PATH I33
J 0
(-9050 4825);
DISPLAY 1.021277 (-9050 4825);
PAINT ORANGE (-9050 4825);
DISPLAY INVISIBLE (-9050 4825);
FORCEPROP 2 LAST CDS_LIB mstr_standard
J 0
(-9100 4750);
PAINT MONO (-9100 4750);
DISPLAY INVISIBLE (-9100 4750);
FORCEPROP 1 LAST OFFPAGE TRUE
J 2
(-9425 4625);
DISPLAY 0.872340 (-9425 4625);
PAINT GREEN (-9425 4625);
DISPLAY INVISIBLE (-9425 4625);
FORCEPROP 1 LAST COMMENT_BODY TRUE
J 2
(-9075 4650);
DISPLAY 0.872340 (-9075 4650);
PAINT GREEN (-9075 4650);
DISPLAY INVISIBLE (-9075 4650);
FORCEADD RES..1
(-6800 4750);
FORCEPROP 0 LAST GROUP AST2500
J 0
(-6872 4385);
DISPLAY 0.638298 (-6872 4385);
PAINT BROWN (-6872 4385);
DISPLAY BOTH (-6872 4385);
FORCEPROP 1 LAST LOCATION R25W133
J 0
(-6900 4800);
DISPLAY 0.617021 (-6900 4800);
PAINT AQUA (-6900 4800);
FORCEPROP 1 LAST PART_NUMBER G21796-074
J 0
(-6875 4475);
DISPLAY 0.617021 (-6875 4475);
PAINT BLUE (-6875 4475);
FORCEPROP 1 LAST PACK_TYPE 0402
J 0
(-6875 4425);
DISPLAY 0.617021 (-6875 4425);
PAINT SKYBLUE (-6875 4425);
FORCEPROP 1 LAST MATERIAL CHIP
J 0
(-6875 4525);
DISPLAY 0.617021 (-6875 4525);
PAINT SKYBLUE (-6875 4525);
FORCEPROP 1 LAST WATTAGE 1/16W
J 2
(-6750 4575);
DISPLAY 0.617021 (-6750 4575);
PAINT SKYBLUE (-6750 4575);
FORCEPROP 1 LASTPIN (-6700 4750) $PN 2
J 0
(-6738 4762);
DISPLAY 0.617021 (-6738 4762);
PAINT ORANGE (-6738 4762);
FORCEPROP 1 LASTPIN (-6900 4750) $PN 1
J 0
(-6888 4762);
DISPLAY 0.617021 (-6888 4762);
PAINT ORANGE (-6888 4762);
FORCEPROP 1 LAST VALUE 33.2
J 2
(-6800 4675);
DISPLAY 0.617021 (-6800 4675);
PAINT SKYBLUE (-6800 4675);
FORCEPROP 1 LAST TOLERANCE 1%
J 0
(-6875 4625);
DISPLAY 0.617021 (-6875 4625);
PAINT SKYBLUE (-6875 4625);
FORCEPROP 1 LAST PATH I34
J 0
(-6850 4900);
DISPLAY 0.978723 (-6850 4900);
PAINT WHITE (-6850 4900);
DISPLAY INVISIBLE (-6850 4900);
FORCEPROP 2 LAST SEC_TYPE 0402
J 0
(-6850 4950);
DISPLAY 1.021277 (-6850 4950);
PAINT ORANGE (-6850 4950);
DISPLAY INVISIBLE (-6850 4950);
FORCEPROP 2 LAST SEC 1
J 0
(-6850 4950);
DISPLAY 0.680851 (-6850 4950);
PAINT MONO (-6850 4950);
DISPLAY INVISIBLE (-6850 4950);
FORCEPROP 2 LAST CDS_LIB mstr_discrete
J 0
(-6800 4750);
PAINT MONO (-6800 4750);
DISPLAY INVISIBLE (-6800 4750);
FORCEPROP 2 LAST CDS_LOCATION R25W133
J 0
(-6850 4800);
DISPLAY 0.617021 (-6850 4800);
PAINT AQUA (-6850 4800);
DISPLAY INVISIBLE (-6850 4800);
FORCEADD CAP..2
R 3
(-6550 4550);
FORCEPROP 1 LASTPIN (-6550 4450) $PN 2
J 2
(-6490 4465);
DISPLAY 0.787234 (-6490 4465);
PAINT ORANGE (-6490 4465);
FORCEPROP 1 LAST PART_NUMBER A36095-026
J 1
(-6350 4425);
DISPLAY 0.617021 (-6350 4425);
PAINT BLUE (-6350 4425);
FORCEPROP 1 LAST PACK_TYPE 0402LF
J 1
(-6375 4375);
DISPLAY 0.617021 (-6375 4375);
PAINT SKYBLUE (-6375 4375);
FORCEPROP 1 LAST LOCATION C25W78
J 1
(-6400 4675);
DISPLAY 0.617021 (-6400 4675);
PAINT AQUA (-6400 4675);
FORCEPROP 1 LAST VOLTAGE 50V
J 2
(-6375 4525);
DISPLAY 0.617021 (-6375 4525);
PAINT SKYBLUE (-6375 4525);
FORCEPROP 1 LAST MATERIAL COG
J 2
(-6350 4475);
DISPLAY 0.617021 (-6350 4475);
PAINT SKYBLUE (-6350 4475);
FORCEPROP 1 LAST TOLERANCE 5%
J 0
(-6450 4575);
DISPLAY 0.617021 (-6450 4575);
PAINT SKYBLUE (-6450 4575);
FORCEPROP 1 LAST VALUE 100.0PF
J 0
(-6450 4625);
DISPLAY 0.617021 (-6450 4625);
PAINT SKYBLUE (-6450 4625);
FORCEPROP 1 LASTPIN (-6550 4650) $PN 1
J 2
(-6490 4610);
DISPLAY 0.787234 (-6490 4610);
PAINT ORANGE (-6490 4610);
FORCEPROP 0 LAST GROUP AST2500
J 0
(-6447 4335);
DISPLAY 0.638298 (-6447 4335);
PAINT BROWN (-6447 4335);
DISPLAY BOTH (-6447 4335);
FORCEPROP 1 LAST PATH I35
R 1
J 2
(-6750 4550);
DISPLAY 0.978723 (-6750 4550);
PAINT WHITE (-6750 4550);
DISPLAY INVISIBLE (-6750 4550);
FORCEPROP 2 LAST SEC 1
J 0
(-6500 4675);
DISPLAY 0.680851 (-6500 4675);
PAINT MONO (-6500 4675);
DISPLAY INVISIBLE (-6500 4675);
FORCEPROP 2 LAST SEC_TYPE 0402LF
J 0
(-6500 4675);
DISPLAY 1.021277 (-6500 4675);
PAINT ORANGE (-6500 4675);
DISPLAY INVISIBLE (-6500 4675);
FORCEPROP 2 LAST CDS_LIB mstr_discrete
R 1
J 0
(-6550 4550);
PAINT MONO (-6550 4550);
DISPLAY INVISIBLE (-6550 4550);
FORCEPROP 2 LAST ROOM PVPP_KLM_VR
R 1
J 2
(-6675 4550);
DISPLAY 0.765957 (-6675 4550);
PAINT GREEN (-6675 4550);
DISPLAY INVISIBLE (-6675 4550);
FORCEPROP 2 LAST BOM_COST PVPP_KLM_VR
R 1
J 0
(-6710 4505);
DISPLAY 1.042553 (-6710 4505);
PAINT WHITE (-6710 4505);
DISPLAY INVISIBLE (-6710 4505);
FORCEPROP 2 LAST REUSE_ID 27
R 1
J 0
(-6800 4550);
DISPLAY 1.042553 (-6800 4550);
PAINT ORANGE (-6800 4550);
DISPLAY INVISIBLE (-6800 4550);
FORCEADD GND..1
(-6550 4350);
FORCEPROP 3 LASTPIN (-6550 4400) SIG_NAME GND\g
J 0
(-6540 4410);
DISPLAY 0.659574 (-6540 4410);
PAINT MONO (-6540 4410);
DISPLAY INVISIBLE (-6540 4410);
FORCEPROP 1 LAST PATH I36
J 0
(-6475 4350);
DISPLAY 0.872340 (-6475 4350);
PAINT AQUA (-6475 4350);
DISPLAY INVISIBLE (-6475 4350);
FORCEPROP 2 LAST CDS_LIB mstr_symbols
J 0
(-6550 4350);
PAINT MONO (-6550 4350);
DISPLAY INVISIBLE (-6550 4350);
FORCEPROP 1 LAST VOLTAGE 0.0V
J 0
(-6611 4323);
DISPLAY 0.340426 (-6611 4323);
PAINT SKYBLUE (-6611 4323);
DISPLAY INVISIBLE (-6611 4323);
FORCEPROP 1 LAST SIZE 1B
J 0
(-6516 4341);
DISPLAY 0.872340 (-6516 4341);
PAINT AQUA (-6516 4341);
DISPLAY INVISIBLE (-6516 4341);
FORCEPROP 1 LAST BODY_TYPE PLUMBING
J 0
(-6611 4323);
DISPLAY 0.340426 (-6611 4323);
PAINT GREEN (-6611 4323);
DISPLAY INVISIBLE (-6611 4323);
FORCEPROP 1 LAST HDL_POWER GND
J 0
(-6591 4541);
DISPLAY 0.872340 (-6591 4541);
PAINT GREEN (-6591 4541);
DISPLAY INVISIBLE (-6591 4541);
FORCEADD RES..1
(-6800 3500);
FORCEPROP 0 LAST GROUP AST2500
J 0
(-6872 3135);
DISPLAY 0.638298 (-6872 3135);
PAINT BROWN (-6872 3135);
DISPLAY BOTH (-6872 3135);
FORCEPROP 1 LAST LOCATION R25W136
J 0
(-6900 3550);
DISPLAY 0.617021 (-6900 3550);
PAINT AQUA (-6900 3550);
FORCEPROP 1 LASTPIN (-6700 3500) $PN 2
J 0
(-6738 3512);
DISPLAY 0.617021 (-6738 3512);
PAINT ORANGE (-6738 3512);
FORCEPROP 1 LAST PACK_TYPE 0402
J 0
(-6875 3175);
DISPLAY 0.617021 (-6875 3175);
PAINT SKYBLUE (-6875 3175);
FORCEPROP 1 LAST PART_NUMBER G21796-074
J 0
(-6875 3225);
DISPLAY 0.617021 (-6875 3225);
PAINT BLUE (-6875 3225);
FORCEPROP 1 LAST VALUE 33.2
J 2
(-6800 3425);
DISPLAY 0.617021 (-6800 3425);
PAINT SKYBLUE (-6800 3425);
FORCEPROP 1 LAST TOLERANCE 1%
J 0
(-6875 3375);
DISPLAY 0.617021 (-6875 3375);
PAINT SKYBLUE (-6875 3375);
FORCEPROP 1 LAST MATERIAL CHIP
J 0
(-6875 3275);
DISPLAY 0.617021 (-6875 3275);
PAINT SKYBLUE (-6875 3275);
FORCEPROP 1 LASTPIN (-6900 3500) $PN 1
J 0
(-6888 3512);
DISPLAY 0.617021 (-6888 3512);
PAINT ORANGE (-6888 3512);
FORCEPROP 1 LAST WATTAGE 1/16W
J 2
(-6750 3325);
DISPLAY 0.617021 (-6750 3325);
PAINT SKYBLUE (-6750 3325);
FORCEPROP 2 LAST CDS_LIB mstr_discrete
J 0
(-6800 3500);
PAINT MONO (-6800 3500);
DISPLAY INVISIBLE (-6800 3500);
FORCEPROP 2 LAST SEC 1
J 0
(-6850 3700);
DISPLAY 0.680851 (-6850 3700);
PAINT MONO (-6850 3700);
DISPLAY INVISIBLE (-6850 3700);
FORCEPROP 2 LAST SEC_TYPE 0402
J 0
(-6850 3700);
DISPLAY 1.021277 (-6850 3700);
PAINT ORANGE (-6850 3700);
DISPLAY INVISIBLE (-6850 3700);
FORCEPROP 1 LAST PATH I38
J 0
(-6850 3650);
DISPLAY 0.978723 (-6850 3650);
PAINT WHITE (-6850 3650);
DISPLAY INVISIBLE (-6850 3650);
FORCEPROP 2 LAST CDS_LOCATION R25W136
J 0
(-6850 3550);
DISPLAY 0.617021 (-6850 3550);
PAINT AQUA (-6850 3550);
DISPLAY INVISIBLE (-6850 3550);
FORCEADD CAP..2
R 3
(-6550 3300);
FORCEPROP 1 LAST TOLERANCE 5%
J 0
(-6450 3325);
DISPLAY 0.617021 (-6450 3325);
PAINT SKYBLUE (-6450 3325);
FORCEPROP 1 LAST VOLTAGE 50V
J 2
(-6375 3275);
DISPLAY 0.617021 (-6375 3275);
PAINT SKYBLUE (-6375 3275);
FORCEPROP 1 LAST MATERIAL COG
J 2
(-6350 3225);
DISPLAY 0.617021 (-6350 3225);
PAINT SKYBLUE (-6350 3225);
FORCEPROP 1 LAST PACK_TYPE 0402LF
J 1
(-6375 3125);
DISPLAY 0.617021 (-6375 3125);
PAINT SKYBLUE (-6375 3125);
FORCEPROP 1 LASTPIN (-6550 3400) $PN 1
J 2
(-6490 3360);
DISPLAY 0.787234 (-6490 3360);
PAINT ORANGE (-6490 3360);
FORCEPROP 1 LASTPIN (-6550 3200) $PN 2
J 2
(-6490 3215);
DISPLAY 0.787234 (-6490 3215);
PAINT ORANGE (-6490 3215);
FORCEPROP 1 LAST PART_NUMBER A36095-026
J 1
(-6350 3175);
DISPLAY 0.617021 (-6350 3175);
PAINT BLUE (-6350 3175);
FORCEPROP 1 LAST VALUE 100.0PF
J 0
(-6450 3375);
DISPLAY 0.617021 (-6450 3375);
PAINT SKYBLUE (-6450 3375);
FORCEPROP 1 LAST LOCATION C25W79
J 1
(-6400 3425);
DISPLAY 0.617021 (-6400 3425);
PAINT AQUA (-6400 3425);
FORCEPROP 0 LAST GROUP AST2500
J 0
(-6472 3085);
DISPLAY 0.638298 (-6472 3085);
PAINT BROWN (-6472 3085);
DISPLAY BOTH (-6472 3085);
FORCEPROP 2 LAST REUSE_ID 27
R 1
J 0
(-6800 3300);
DISPLAY 1.042553 (-6800 3300);
PAINT ORANGE (-6800 3300);
DISPLAY INVISIBLE (-6800 3300);
FORCEPROP 2 LAST BOM_COST PVPP_KLM_VR
R 1
J 0
(-6710 3255);
DISPLAY 1.042553 (-6710 3255);
PAINT WHITE (-6710 3255);
DISPLAY INVISIBLE (-6710 3255);
FORCEPROP 2 LAST ROOM PVPP_KLM_VR
R 1
J 2
(-6675 3300);
DISPLAY 0.765957 (-6675 3300);
PAINT GREEN (-6675 3300);
DISPLAY INVISIBLE (-6675 3300);
FORCEPROP 2 LAST CDS_LIB mstr_discrete
R 1
J 0
(-6550 3300);
PAINT MONO (-6550 3300);
DISPLAY INVISIBLE (-6550 3300);
FORCEPROP 2 LAST SEC_TYPE 0402LF
J 0
(-6500 3425);
DISPLAY 1.021277 (-6500 3425);
PAINT ORANGE (-6500 3425);
DISPLAY INVISIBLE (-6500 3425);
FORCEPROP 2 LAST SEC 1
J 0
(-6500 3425);
DISPLAY 0.680851 (-6500 3425);
PAINT MONO (-6500 3425);
DISPLAY INVISIBLE (-6500 3425);
FORCEPROP 1 LAST PATH I39
R 1
J 2
(-6750 3300);
DISPLAY 0.978723 (-6750 3300);
PAINT WHITE (-6750 3300);
DISPLAY INVISIBLE (-6750 3300);
FORCEADD GND..1
(-6550 3100);
FORCEPROP 3 LASTPIN (-6550 3150) SIG_NAME GND\g
J 0
(-6540 3160);
DISPLAY 0.659574 (-6540 3160);
PAINT MONO (-6540 3160);
DISPLAY INVISIBLE (-6540 3160);
FORCEPROP 1 LAST PATH I40
J 0
(-6475 3100);
DISPLAY 0.872340 (-6475 3100);
PAINT AQUA (-6475 3100);
DISPLAY INVISIBLE (-6475 3100);
FORCEPROP 2 LAST CDS_LIB mstr_symbols
J 0
(-6550 3100);
PAINT MONO (-6550 3100);
DISPLAY INVISIBLE (-6550 3100);
FORCEPROP 1 LAST VOLTAGE 0.0V
J 0
(-6611 3073);
DISPLAY 0.340426 (-6611 3073);
PAINT SKYBLUE (-6611 3073);
DISPLAY INVISIBLE (-6611 3073);
FORCEPROP 1 LAST SIZE 1B
J 0
(-6516 3091);
DISPLAY 0.872340 (-6516 3091);
PAINT AQUA (-6516 3091);
DISPLAY INVISIBLE (-6516 3091);
FORCEPROP 1 LAST BODY_TYPE PLUMBING
J 0
(-6611 3073);
DISPLAY 0.340426 (-6611 3073);
PAINT GREEN (-6611 3073);
DISPLAY INVISIBLE (-6611 3073);
FORCEPROP 1 LAST HDL_POWER GND
J 0
(-6591 3291);
DISPLAY 0.872340 (-6591 3291);
PAINT GREEN (-6591 3291);
DISPLAY INVISIBLE (-6591 3291);
FORCEADD W_VCC_CIRCLE..1
(-7750 3900);
FORCEPROP 3 LASTPIN (-7750 3900) SIG_NAME P5V_VGA_D\g
J 0
(-7740 3910);
DISPLAY 0.659574 (-7740 3910);
PAINT MONO (-7740 3910);
DISPLAY INVISIBLE (-7740 3910);
FORCEPROP 1 LAST HDL_POWER P5V_VGA_D
J 1
(-7729 3975);
DISPLAY 0.872340 (-7729 3975);
PAINT ORANGE (-7729 3975);
FORCEPROP 2 LAST CDS_LIB w_power
J 0
(-7750 3900);
PAINT MONO (-7750 3900);
DISPLAY INVISIBLE (-7750 3900);
FORCEPROP 1 LAST CDS_LMAN_SYM_OUTLINE -100,100,100,-100
J 0
(-7750 3900);
DISPLAY 0.468085 (-7750 3900);
PAINT GREEN (-7750 3900);
DISPLAY INVISIBLE (-7750 3900);
FORCEPROP 1 LAST PATH I41
J 0
(-7750 3900);
DISPLAY 0.617021 (-7750 3900);
PAINT GREEN (-7750 3900);
DISPLAY INVISIBLE (-7750 3900);
FORCEPROP 1 LAST BODY_TYPE PLUMBING
J 0
(-7738 3894);
DISPLAY 0.340426 (-7738 3894);
PAINT GREEN (-7738 3894);
DISPLAY INVISIBLE (-7738 3894);
FORCEADD P3V3..1
(-8200 4300);
FORCEPROP 3 LASTPIN (-8200 4250) SIG_NAME P3V3\g
J 0
(-8190 4260);
DISPLAY 0.659574 (-8190 4260);
PAINT MONO (-8190 4260);
DISPLAY INVISIBLE (-8190 4260);
FORCEPROP 2 LAST CDS_LIB mstr_symbols
J 0
(-8200 4300);
PAINT MONO (-8200 4300);
DISPLAY INVISIBLE (-8200 4300);
FORCEPROP 1 LAST SIZE 1B
J 0
(-8155 4322);
DISPLAY 0.340426 (-8155 4322);
PAINT GREEN (-8155 4322);
DISPLAY INVISIBLE (-8155 4322);
FORCEPROP 1 LAST VOLTAGE 3.3V
J 0
(-8245 4257);
DISPLAY 0.340426 (-8245 4257);
PAINT SKYBLUE (-8245 4257);
DISPLAY INVISIBLE (-8245 4257);
FORCEPROP 1 LAST PATH I42
J 0
(-8155 4302);
DISPLAY 0.340426 (-8155 4302);
PAINT GREEN (-8155 4302);
DISPLAY INVISIBLE (-8155 4302);
FORCEPROP 1 LAST BODY_TYPE PLUMBING
J 0
(-8245 4257);
DISPLAY 0.340426 (-8245 4257);
PAINT GREEN (-8245 4257);
DISPLAY INVISIBLE (-8245 4257);
FORCEPROP 1 LAST HDL_POWER P3V3
J 0
(-8525 4175);
DISPLAY 0.872340 (-8525 4175);
PAINT ORANGE (-8525 4175);
DISPLAY INVISIBLE (-8525 4175);
FORCEADD RES..2
(-8200 4050);
FORCEPROP 1 LAST LOCATION R25W134
J 0
(-8155 4200);
DISPLAY 0.617021 (-8155 4200);
PAINT AQUA (-8155 4200);
FORCEPROP 1 LAST PART_NUMBER G21796-072
J 0
(-8160 3950);
DISPLAY 0.617021 (-8160 3950);
PAINT BLUE (-8160 3950);
FORCEPROP 1 LASTPIN (-8200 3950) $PN 2
J 0
(-8195 3960);
DISPLAY 0.617021 (-8195 3960);
PAINT ORANGE (-8195 3960);
FORCEPROP 1 LASTPIN (-8200 4150) $PN 1
J 0
(-8195 4162);
DISPLAY 0.617021 (-8195 4162);
PAINT ORANGE (-8195 4162);
FORCEPROP 1 LAST TOLERANCE 1%
J 0
(-8155 4100);
DISPLAY 0.617021 (-8155 4100);
PAINT SKYBLUE (-8155 4100);
FORCEPROP 1 LAST VALUE 4.75K
J 0
(-8155 4150);
DISPLAY 0.617021 (-8155 4150);
PAINT SKYBLUE (-8155 4150);
FORCEPROP 1 LAST WATTAGE 1/16W
J 0
(-8160 4050);
DISPLAY 0.617021 (-8160 4050);
PAINT SKYBLUE (-8160 4050);
FORCEPROP 1 LAST MATERIAL CHIP
J 0
(-8160 4000);
DISPLAY 0.617021 (-8160 4000);
PAINT SKYBLUE (-8160 4000);
FORCEPROP 1 LAST PACK_TYPE 0402
J 0
(-8160 3900);
DISPLAY 0.617021 (-8160 3900);
PAINT SKYBLUE (-8160 3900);
FORCEPROP 0 LAST GROUP AST2500
J 0
(-8150 3850);
DISPLAY 0.638298 (-8150 3850);
PAINT BROWN (-8150 3850);
DISPLAY BOTH (-8150 3850);
FORCEPROP 0 LAST BOM_COST SM_THERM
J 0
(-8150 4375);
DISPLAY 1.021277 (-8150 4375);
PAINT ORANGE (-8150 4375);
DISPLAY INVISIBLE (-8150 4375);
FORCEPROP 2 LAST SEC_TYPE 0402
J 0
(-8150 4275);
DISPLAY 1.021277 (-8150 4275);
PAINT ORANGE (-8150 4275);
DISPLAY INVISIBLE (-8150 4275);
FORCEPROP 2 LAST SEC 1
J 0
(-8150 4275);
DISPLAY 0.680851 (-8150 4275);
PAINT MONO (-8150 4275);
DISPLAY INVISIBLE (-8150 4275);
FORCEPROP 0 LAST ROOM CPU_FANS
J 0
(-8150 4275);
DISPLAY 1.021277 (-8150 4275);
PAINT ORANGE (-8150 4275);
DISPLAY INVISIBLE (-8150 4275);
FORCEPROP 2 LAST CDS_LIB mstr_discrete
J 0
(-8200 4050);
PAINT ORANGE (-8200 4050);
DISPLAY INVISIBLE (-8200 4050);
FORCEPROP 0 LAST CDS_SEC 1
J 0
(-8150 4225);
PAINT MONO (-8150 4225);
DISPLAY INVISIBLE (-8150 4225);
FORCEPROP 1 LAST PATH I43
J 0
(-8150 4225);
DISPLAY 0.978723 (-8150 4225);
PAINT WHITE (-8150 4225);
DISPLAY INVISIBLE (-8150 4225);
FORCEPROP 2 LAST CDS_LOCATION R25W134
J 0
(-8155 4175);
DISPLAY 0.617021 (-8155 4175);
PAINT AQUA (-8155 4175);
DISPLAY INVISIBLE (-8155 4175);
FORCEADD RES..2
(-7750 3700);
FORCEPROP 1 LAST WATTAGE 1/16W
J 0
(-7710 3700);
DISPLAY 0.617021 (-7710 3700);
PAINT SKYBLUE (-7710 3700);
FORCEPROP 1 LAST TOLERANCE 1%
J 0
(-7705 3750);
DISPLAY 0.617021 (-7705 3750);
PAINT SKYBLUE (-7705 3750);
FORCEPROP 1 LAST PACK_TYPE 0402
J 0
(-7710 3550);
DISPLAY 0.617021 (-7710 3550);
PAINT SKYBLUE (-7710 3550);
FORCEPROP 1 LAST MATERIAL CHIP
J 0
(-7710 3650);
DISPLAY 0.617021 (-7710 3650);
PAINT SKYBLUE (-7710 3650);
FORCEPROP 1 LAST PART_NUMBER G21796-072
J 0
(-7710 3600);
DISPLAY 0.617021 (-7710 3600);
PAINT BLUE (-7710 3600);
FORCEPROP 0 LAST GROUP AST2500
J 0
(-7550 3700);
DISPLAY 0.638298 (-7550 3700);
PAINT BROWN (-7550 3700);
DISPLAY BOTH (-7550 3700);
FORCEPROP 1 LAST LOCATION R25W135
J 0
(-7705 3850);
DISPLAY 0.617021 (-7705 3850);
PAINT AQUA (-7705 3850);
FORCEPROP 1 LAST VALUE 4.75K
J 0
(-7705 3800);
DISPLAY 0.617021 (-7705 3800);
PAINT SKYBLUE (-7705 3800);
FORCEPROP 0 LAST BOM_COST SM_THERM
J 0
(-7700 4025);
DISPLAY 1.021277 (-7700 4025);
PAINT ORANGE (-7700 4025);
DISPLAY INVISIBLE (-7700 4025);
FORCEPROP 0 LAST ROOM CPU_FANS
J 0
(-7700 3925);
DISPLAY 1.021277 (-7700 3925);
PAINT ORANGE (-7700 3925);
DISPLAY INVISIBLE (-7700 3925);
FORCEPROP 2 LAST CDS_LIB mstr_discrete
J 0
(-7750 3700);
PAINT MONO (-7750 3700);
DISPLAY INVISIBLE (-7750 3700);
FORCEPROP 1 LAST PATH I44
J 0
(-7700 3875);
DISPLAY 0.978723 (-7700 3875);
PAINT WHITE (-7700 3875);
DISPLAY INVISIBLE (-7700 3875);
FORCEPROP 1 LASTPIN (-7750 3600) $PN 2
J 0
(-7745 3610);
DISPLAY 0.787234 (-7745 3610);
PAINT ORANGE (-7745 3610);
DISPLAY INVISIBLE (-7745 3610);
FORCEPROP 1 LASTPIN (-7750 3800) $PN 1
J 0
(-7745 3762);
DISPLAY 0.787234 (-7745 3762);
PAINT ORANGE (-7745 3762);
DISPLAY INVISIBLE (-7745 3762);
FORCEADD OFFPAGE..3
R 2
(-9100 3500);
FORCEPROP 2 LAST $XR0 146 
J 0
(-9380 3500);
DISPLAY 0.638298 (-9380 3500);
PAINT MONO (-9380 3500);
FORCEPROP 2 LAST PATH I46
J 0
(-9050 3575);
DISPLAY 1.021277 (-9050 3575);
PAINT ORANGE (-9050 3575);
DISPLAY INVISIBLE (-9050 3575);
FORCEPROP 2 LAST CDS_LIB mstr_standard
J 0
(-9100 3500);
PAINT MONO (-9100 3500);
DISPLAY INVISIBLE (-9100 3500);
FORCEPROP 1 LAST OFFPAGE TRUE
J 2
(-9425 3375);
DISPLAY 0.872340 (-9425 3375);
PAINT GREEN (-9425 3375);
DISPLAY INVISIBLE (-9425 3375);
FORCEPROP 1 LAST COMMENT_BODY TRUE
J 2
(-9050 3400);
DISPLAY 0.872340 (-9050 3400);
PAINT GREEN (-9050 3400);
DISPLAY INVISIBLE (-9050 3400);
FORCEADD RES..1
(-3250 5000);
FORCEPROP 0 LAST GROUP AST2500
J 0
(-3460 4828);
DISPLAY 0.638298 (-3460 4828);
PAINT BROWN (-3460 4828);
DISPLAY BOTH (-3460 4828);
FORCEPROP 1 LAST PACK_TYPE 0402
J 0
(-3025 4875);
DISPLAY 0.617021 (-3025 4875);
PAINT SKYBLUE (-3025 4875);
FORCEPROP 1 LAST WATTAGE 1/16W
J 2
(-2875 4925);
DISPLAY 0.617021 (-2875 4925);
PAINT SKYBLUE (-2875 4925);
FORCEPROP 1 LAST TOLERANCE 1%
J 0
(-3100 4925);
DISPLAY 0.617021 (-3100 4925);
PAINT SKYBLUE (-3100 4925);
FORCEPROP 1 LAST LOCATION R25W138
J 0
(-3450 4925);
DISPLAY 0.617021 (-3450 4925);
PAINT AQUA (-3450 4925);
FORCEPROP 1 LASTPIN (-3350 5000) $PN 1
J 0
(-3338 5012);
DISPLAY 0.617021 (-3338 5012);
PAINT ORANGE (-3338 5012);
FORCEPROP 1 LAST PART_NUMBER G21796-074
J 0
(-3300 4875);
DISPLAY 0.617021 (-3300 4875);
PAINT BLUE (-3300 4875);
FORCEPROP 1 LASTPIN (-3150 5000) $PN 2
J 0
(-3188 5012);
DISPLAY 0.617021 (-3188 5012);
PAINT ORANGE (-3188 5012);
FORCEPROP 1 LAST MATERIAL CHIP
J 0
(-3450 4875);
DISPLAY 0.617021 (-3450 4875);
PAINT SKYBLUE (-3450 4875);
FORCEPROP 1 LAST VALUE 33.2
J 2
(-3150 4925);
DISPLAY 0.617021 (-3150 4925);
PAINT SKYBLUE (-3150 4925);
FORCEPROP 2 LAST CDS_LOCATION R25W138
J 0
(-3300 5050);
DISPLAY 0.617021 (-3300 5050);
PAINT AQUA (-3300 5050);
DISPLAY INVISIBLE (-3300 5050);
FORCEPROP 2 LAST CDS_LIB mstr_discrete
J 0
(-3250 5000);
PAINT ORANGE (-3250 5000);
DISPLAY INVISIBLE (-3250 5000);
FORCEPROP 2 LAST ROOM PROC_TRANSLATORS
J 0
(-3300 5100);
DISPLAY 1.021277 (-3300 5100);
PAINT ORANGE (-3300 5100);
DISPLAY INVISIBLE (-3300 5100);
FORCEPROP 2 LAST SEC_TYPE 0402
J 0
(-3300 5200);
DISPLAY 1.021277 (-3300 5200);
PAINT ORANGE (-3300 5200);
DISPLAY INVISIBLE (-3300 5200);
FORCEPROP 2 LAST BOM_COST PROC_SIDEBAND
J 0
(-3300 5150);
DISPLAY 1.021277 (-3300 5150);
PAINT ORANGE (-3300 5150);
DISPLAY INVISIBLE (-3300 5150);
FORCEPROP 2 LAST SEC 1
J 0
(-3300 5200);
DISPLAY 0.680851 (-3300 5200);
PAINT MONO (-3300 5200);
DISPLAY INVISIBLE (-3300 5200);
FORCEPROP 1 LAST PATH I49
J 0
(-3300 5150);
DISPLAY 0.978723 (-3300 5150);
PAINT WHITE (-3300 5150);
DISPLAY INVISIBLE (-3300 5150);
FORCEADD OFFPAGE..4
R 2
(-5400 5100);
FORCEPROP 2 LAST $XR0 146 
J 0
(-5652 5100);
DISPLAY 0.638298 (-5652 5100);
PAINT MONO (-5652 5100);
FORCEPROP 2 LAST CDS_LIB mstr_standard
J 0
(-5400 5100);
PAINT MONO (-5400 5100);
DISPLAY INVISIBLE (-5400 5100);
FORCEPROP 2 LAST PATH I54
J 0
(-5350 5175);
DISPLAY 1.021277 (-5350 5175);
PAINT ORANGE (-5350 5175);
DISPLAY INVISIBLE (-5350 5175);
FORCEPROP 1 LAST OFFPAGE TRUE
J 2
(-5725 4975);
DISPLAY 0.872340 (-5725 4975);
PAINT GREEN (-5725 4975);
DISPLAY INVISIBLE (-5725 4975);
FORCEPROP 1 LAST COMMENT_BODY TRUE
J 2
(-5375 5000);
DISPLAY 0.872340 (-5375 5000);
PAINT GREEN (-5375 5000);
DISPLAY INVISIBLE (-5375 5000);
FORCEADD OFFPAGE..4
R 2
(-5400 4550);
FORCEPROP 2 LAST $XR0 146 
J 0
(-5652 4550);
DISPLAY 0.638298 (-5652 4550);
PAINT MONO (-5652 4550);
FORCEPROP 2 LAST PATH I55
J 0
(-5350 4625);
DISPLAY 1.021277 (-5350 4625);
PAINT ORANGE (-5350 4625);
DISPLAY INVISIBLE (-5350 4625);
FORCEPROP 2 LAST CDS_LIB mstr_standard
J 0
(-5400 4550);
PAINT MONO (-5400 4550);
DISPLAY INVISIBLE (-5400 4550);
FORCEPROP 1 LAST OFFPAGE TRUE
J 2
(-5725 4425);
DISPLAY 0.872340 (-5725 4425);
PAINT GREEN (-5725 4425);
DISPLAY INVISIBLE (-5725 4425);
FORCEPROP 1 LAST COMMENT_BODY TRUE
J 2
(-5375 4450);
DISPLAY 0.872340 (-5375 4450);
PAINT GREEN (-5375 4450);
DISPLAY INVISIBLE (-5375 4450);
FORCEADD RES..1
(-3250 4450);
FORCEPROP 1 LASTPIN (-3350 4450) $PN 1
J 0
(-3338 4462);
DISPLAY 0.617021 (-3338 4462);
PAINT ORANGE (-3338 4462);
FORCEPROP 1 LAST LOCATION R25W139
J 0
(-3450 4375);
DISPLAY 0.617021 (-3450 4375);
PAINT AQUA (-3450 4375);
FORCEPROP 1 LAST PART_NUMBER G21796-074
J 0
(-3300 4325);
DISPLAY 0.617021 (-3300 4325);
PAINT BLUE (-3300 4325);
FORCEPROP 0 LAST GROUP AST2500
J 0
(-3460 4278);
DISPLAY 0.638298 (-3460 4278);
PAINT BROWN (-3460 4278);
DISPLAY BOTH (-3460 4278);
FORCEPROP 1 LASTPIN (-3150 4450) $PN 2
J 0
(-3188 4462);
DISPLAY 0.617021 (-3188 4462);
PAINT ORANGE (-3188 4462);
FORCEPROP 1 LAST MATERIAL CHIP
J 0
(-3450 4325);
DISPLAY 0.617021 (-3450 4325);
PAINT SKYBLUE (-3450 4325);
FORCEPROP 1 LAST VALUE 33.2
J 2
(-3150 4375);
DISPLAY 0.617021 (-3150 4375);
PAINT SKYBLUE (-3150 4375);
FORCEPROP 1 LAST PACK_TYPE 0402
J 0
(-3025 4325);
DISPLAY 0.617021 (-3025 4325);
PAINT SKYBLUE (-3025 4325);
FORCEPROP 1 LAST TOLERANCE 1%
J 0
(-3100 4375);
DISPLAY 0.617021 (-3100 4375);
PAINT SKYBLUE (-3100 4375);
FORCEPROP 1 LAST WATTAGE 1/16W
J 2
(-2875 4375);
DISPLAY 0.617021 (-2875 4375);
PAINT SKYBLUE (-2875 4375);
FORCEPROP 1 LAST PATH I59
J 0
(-3300 4600);
DISPLAY 0.978723 (-3300 4600);
PAINT WHITE (-3300 4600);
DISPLAY INVISIBLE (-3300 4600);
FORCEPROP 2 LAST CDS_LIB mstr_discrete
J 0
(-3250 4450);
PAINT ORANGE (-3250 4450);
DISPLAY INVISIBLE (-3250 4450);
FORCEPROP 2 LAST ROOM PROC_TRANSLATORS
J 0
(-3300 4550);
DISPLAY 1.021277 (-3300 4550);
PAINT ORANGE (-3300 4550);
DISPLAY INVISIBLE (-3300 4550);
FORCEPROP 2 LAST SEC_TYPE 0402
J 0
(-3300 4650);
DISPLAY 1.021277 (-3300 4650);
PAINT ORANGE (-3300 4650);
DISPLAY INVISIBLE (-3300 4650);
FORCEPROP 2 LAST BOM_COST PROC_SIDEBAND
J 0
(-3300 4600);
DISPLAY 1.021277 (-3300 4600);
PAINT ORANGE (-3300 4600);
DISPLAY INVISIBLE (-3300 4600);
FORCEPROP 2 LAST SEC 1
J 0
(-3300 4650);
DISPLAY 0.680851 (-3300 4650);
PAINT MONO (-3300 4650);
DISPLAY INVISIBLE (-3300 4650);
FORCEPROP 2 LAST CDS_LOCATION R25W139
J 0
(-3300 4500);
DISPLAY 0.617021 (-3300 4500);
PAINT AQUA (-3300 4500);
DISPLAY INVISIBLE (-3300 4500);
FORCEADD CAP..1
(-2750 4850);
FORCEPROP 1 LAST TOLERANCE 5%
J 0
(-2700 4800);
DISPLAY 0.617021 (-2700 4800);
PAINT SKYBLUE (-2700 4800);
FORCEPROP 1 LASTPIN (-2750 4750) $PN 2
J 0
(-2740 4730);
DISPLAY 0.617021 (-2740 4730);
PAINT ORANGE (-2740 4730);
FORCEPROP 1 LAST VALUE 10.0PF
J 0
(-2700 4900);
DISPLAY 0.617021 (-2700 4900);
PAINT SKYBLUE (-2700 4900);
FORCEPROP 1 LAST VOLTAGE 50V
J 0
(-2700 4850);
DISPLAY 0.617021 (-2700 4850);
PAINT SKYBLUE (-2700 4850);
FORCEPROP 1 LAST LOCATION C25W81
J 0
(-2700 4950);
DISPLAY 0.617021 (-2700 4950);
PAINT AQUA (-2700 4950);
FORCEPROP 1 LASTPIN (-2750 4950) $PN 1
J 0
(-2740 4930);
DISPLAY 0.617021 (-2740 4930);
PAINT ORANGE (-2740 4930);
FORCEPROP 1 LAST MATERIAL COG
J 0
(-2700 4750);
DISPLAY 0.617021 (-2700 4750);
PAINT SKYBLUE (-2700 4750);
FORCEPROP 1 LAST PART_NUMBER A36094-025
J 0
(-2700 4700);
DISPLAY 0.617021 (-2700 4700);
PAINT BLUE (-2700 4700);
FORCEPROP 0 LAST GROUP AST2500
J 0
(-2697 4610);
DISPLAY 0.638298 (-2697 4610);
PAINT BROWN (-2697 4610);
DISPLAY BOTH (-2697 4610);
FORCEPROP 1 LAST PACK_TYPE 0402LF
J 0
(-2700 4650);
DISPLAY 0.617021 (-2700 4650);
PAINT SKYBLUE (-2700 4650);
FORCEPROP 1 LAST PATH I60
J 0
(-2700 5000);
DISPLAY 0.978723 (-2700 5000);
PAINT WHITE (-2700 5000);
DISPLAY INVISIBLE (-2700 5000);
FORCEPROP 2 LAST ROOM BMC_VOLT_MONITOR
J 0
(-2700 5000);
DISPLAY 1.021277 (-2700 5000);
PAINT ORANGE (-2700 5000);
DISPLAY INVISIBLE (-2700 5000);
FORCEPROP 2 LAST SEC 1
J 0
(-2700 5050);
DISPLAY 0.680851 (-2700 5050);
PAINT MONO (-2700 5050);
DISPLAY INVISIBLE (-2700 5050);
FORCEPROP 2 LAST BOM_COST SM_HM
J 0
(-2700 5050);
DISPLAY 1.021277 (-2700 5050);
PAINT ORANGE (-2700 5050);
DISPLAY INVISIBLE (-2700 5050);
FORCEPROP 2 LAST SEC_TYPE 0402LF
J 0
(-2700 5050);
DISPLAY 1.021277 (-2700 5050);
PAINT ORANGE (-2700 5050);
DISPLAY INVISIBLE (-2700 5050);
FORCEPROP 2 LAST CDS_LIB mstr_discrete
J 0
(-2750 4850);
PAINT ORANGE (-2750 4850);
DISPLAY INVISIBLE (-2750 4850);
FORCEPROP 2 LAST CDS_LOCATION C25W81
J 0
(-2700 4950);
DISPLAY 0.617021 (-2700 4950);
PAINT AQUA (-2700 4950);
DISPLAY INVISIBLE (-2700 4950);
FORCEADD GND..1
(-2750 4650);
FORCEPROP 3 LASTPIN (-2750 4700) SIG_NAME GND\g
J 0
(-2740 4710);
DISPLAY 0.659574 (-2740 4710);
PAINT MONO (-2740 4710);
DISPLAY INVISIBLE (-2740 4710);
FORCEPROP 1 LAST PATH I61
J 0
(-2675 4650);
DISPLAY 0.872340 (-2675 4650);
PAINT AQUA (-2675 4650);
DISPLAY INVISIBLE (-2675 4650);
FORCEPROP 2 LAST CDS_LIB mstr_symbols
J 0
(-2750 4650);
PAINT MONO (-2750 4650);
DISPLAY INVISIBLE (-2750 4650);
FORCEPROP 1 LAST VOLTAGE 0.0V
J 0
(-2811 4623);
DISPLAY 0.340426 (-2811 4623);
PAINT SKYBLUE (-2811 4623);
DISPLAY INVISIBLE (-2811 4623);
FORCEPROP 1 LAST SIZE 1B
J 0
(-2716 4641);
DISPLAY 0.872340 (-2716 4641);
PAINT AQUA (-2716 4641);
DISPLAY INVISIBLE (-2716 4641);
FORCEPROP 1 LAST BODY_TYPE PLUMBING
J 0
(-2811 4623);
DISPLAY 0.340426 (-2811 4623);
PAINT GREEN (-2811 4623);
DISPLAY INVISIBLE (-2811 4623);
FORCEPROP 1 LAST HDL_POWER GND
J 0
(-2791 4841);
DISPLAY 0.872340 (-2791 4841);
PAINT GREEN (-2791 4841);
DISPLAY INVISIBLE (-2791 4841);
FORCEADD CAP..1
(-2750 4300);
FORCEPROP 1 LAST PACK_TYPE 0402LF
J 0
(-2700 4100);
DISPLAY 0.617021 (-2700 4100);
PAINT SKYBLUE (-2700 4100);
FORCEPROP 1 LAST PART_NUMBER A36094-025
J 0
(-2700 4150);
DISPLAY 0.617021 (-2700 4150);
PAINT BLUE (-2700 4150);
FORCEPROP 1 LASTPIN (-2750 4200) $PN 2
J 0
(-2740 4180);
DISPLAY 0.617021 (-2740 4180);
PAINT ORANGE (-2740 4180);
FORCEPROP 1 LAST MATERIAL COG
J 0
(-2700 4200);
DISPLAY 0.617021 (-2700 4200);
PAINT SKYBLUE (-2700 4200);
FORCEPROP 1 LAST TOLERANCE 5%
J 0
(-2700 4250);
DISPLAY 0.617021 (-2700 4250);
PAINT SKYBLUE (-2700 4250);
FORCEPROP 1 LASTPIN (-2750 4400) $PN 1
J 0
(-2740 4380);
DISPLAY 0.617021 (-2740 4380);
PAINT ORANGE (-2740 4380);
FORCEPROP 1 LAST VOLTAGE 50V
J 0
(-2700 4300);
DISPLAY 0.617021 (-2700 4300);
PAINT SKYBLUE (-2700 4300);
FORCEPROP 1 LAST VALUE 10.0PF
J 0
(-2700 4350);
DISPLAY 0.617021 (-2700 4350);
PAINT SKYBLUE (-2700 4350);
FORCEPROP 1 LAST LOCATION C25W82
J 0
(-2700 4400);
DISPLAY 0.617021 (-2700 4400);
PAINT AQUA (-2700 4400);
FORCEPROP 0 LAST GROUP AST2500
J 0
(-2697 4060);
DISPLAY 0.638298 (-2697 4060);
PAINT BROWN (-2697 4060);
DISPLAY BOTH (-2697 4060);
FORCEPROP 1 LAST PATH I62
J 0
(-2700 4450);
DISPLAY 0.978723 (-2700 4450);
PAINT WHITE (-2700 4450);
DISPLAY INVISIBLE (-2700 4450);
FORCEPROP 2 LAST CDS_LIB mstr_discrete
J 0
(-2750 4300);
PAINT ORANGE (-2750 4300);
DISPLAY INVISIBLE (-2750 4300);
FORCEPROP 2 LAST SEC_TYPE 0402LF
J 0
(-2700 4500);
DISPLAY 1.021277 (-2700 4500);
PAINT ORANGE (-2700 4500);
DISPLAY INVISIBLE (-2700 4500);
FORCEPROP 2 LAST BOM_COST SM_HM
J 0
(-2700 4500);
DISPLAY 1.021277 (-2700 4500);
PAINT ORANGE (-2700 4500);
DISPLAY INVISIBLE (-2700 4500);
FORCEPROP 2 LAST SEC 1
J 0
(-2700 4500);
DISPLAY 0.680851 (-2700 4500);
PAINT MONO (-2700 4500);
DISPLAY INVISIBLE (-2700 4500);
FORCEPROP 2 LAST ROOM BMC_VOLT_MONITOR
J 0
(-2700 4450);
DISPLAY 1.021277 (-2700 4450);
PAINT ORANGE (-2700 4450);
DISPLAY INVISIBLE (-2700 4450);
FORCEPROP 2 LAST CDS_LOCATION C25W82
J 0
(-2700 4400);
DISPLAY 0.617021 (-2700 4400);
PAINT AQUA (-2700 4400);
DISPLAY INVISIBLE (-2700 4400);
FORCEADD GND..1
(-2750 4100);
FORCEPROP 3 LASTPIN (-2750 4150) SIG_NAME GND\g
J 0
(-2740 4160);
DISPLAY 0.659574 (-2740 4160);
PAINT MONO (-2740 4160);
DISPLAY INVISIBLE (-2740 4160);
FORCEPROP 1 LAST SIZE 1B
J 0
(-2716 4091);
DISPLAY 0.872340 (-2716 4091);
PAINT AQUA (-2716 4091);
DISPLAY INVISIBLE (-2716 4091);
FORCEPROP 1 LAST VOLTAGE 0.0V
J 0
(-2811 4073);
DISPLAY 0.340426 (-2811 4073);
PAINT SKYBLUE (-2811 4073);
DISPLAY INVISIBLE (-2811 4073);
FORCEPROP 2 LAST CDS_LIB mstr_symbols
J 0
(-2750 4100);
PAINT MONO (-2750 4100);
DISPLAY INVISIBLE (-2750 4100);
FORCEPROP 1 LAST PATH I63
J 0
(-2675 4100);
DISPLAY 0.872340 (-2675 4100);
PAINT AQUA (-2675 4100);
DISPLAY INVISIBLE (-2675 4100);
FORCEPROP 1 LAST BODY_TYPE PLUMBING
J 0
(-2811 4073);
DISPLAY 0.340426 (-2811 4073);
PAINT GREEN (-2811 4073);
DISPLAY INVISIBLE (-2811 4073);
FORCEPROP 1 LAST HDL_POWER GND
J 0
(-2791 4291);
DISPLAY 0.872340 (-2791 4291);
PAINT GREEN (-2791 4291);
DISPLAY INVISIBLE (-2791 4291);
FORCEADD CAP..1
(-4900 3450);
FORCEPROP 0 LAST GROUP AST2500
J 0
(-4847 3210);
DISPLAY 0.638298 (-4847 3210);
PAINT BROWN (-4847 3210);
DISPLAY BOTH (-4847 3210);
FORCEPROP 1 LASTPIN (-4900 3550) $PN 1
J 0
(-4890 3530);
DISPLAY 0.787234 (-4890 3530);
PAINT ORANGE (-4890 3530);
FORCEPROP 1 LAST VALUE 12.0PF
J 0
(-4850 3500);
DISPLAY 0.617021 (-4850 3500);
PAINT SKYBLUE (-4850 3500);
FORCEPROP 1 LAST PART_NUMBER A36095-043
J 0
(-4850 3300);
DISPLAY 0.617021 (-4850 3300);
PAINT BLUE (-4850 3300);
FORCEPROP 1 LAST PACK_TYPE 0402LF
J 0
(-4850 3250);
DISPLAY 0.617021 (-4850 3250);
PAINT SKYBLUE (-4850 3250);
FORCEPROP 1 LAST VOLTAGE 50V
J 0
(-4850 3450);
DISPLAY 0.617021 (-4850 3450);
PAINT SKYBLUE (-4850 3450);
FORCEPROP 1 LAST TOLERANCE 5%
J 0
(-4850 3400);
DISPLAY 0.617021 (-4850 3400);
PAINT SKYBLUE (-4850 3400);
FORCEPROP 1 LAST MATERIAL COG
J 0
(-4850 3350);
DISPLAY 0.617021 (-4850 3350);
PAINT SKYBLUE (-4850 3350);
FORCEPROP 1 LASTPIN (-4900 3350) $PN 2
J 0
(-4890 3330);
DISPLAY 0.787234 (-4890 3330);
PAINT ORANGE (-4890 3330);
FORCEPROP 1 LAST LOCATION C25W72
J 0
(-4850 3550);
DISPLAY 0.617021 (-4850 3550);
PAINT AQUA (-4850 3550);
FORCEPROP 2 LAST CDS_LOCATION C25W72
J 0
(-4850 3550);
DISPLAY 0.617021 (-4850 3550);
PAINT AQUA (-4850 3550);
DISPLAY INVISIBLE (-4850 3550);
FORCEPROP 1 LAST PATH I7
J 0
(-4850 3600);
DISPLAY 0.978723 (-4850 3600);
PAINT WHITE (-4850 3600);
DISPLAY INVISIBLE (-4850 3600);
FORCEPROP 2 LAST SEC 1
J 0
(-4850 3650);
PAINT MONO (-4850 3650);
DISPLAY INVISIBLE (-4850 3650);
FORCEPROP 2 LAST SEC_TYPE 0402LF
J 0
(-4850 3650);
DISPLAY 1.021277 (-4850 3650);
PAINT ORANGE (-4850 3650);
DISPLAY INVISIBLE (-4850 3650);
FORCEPROP 2 LAST BOM_COST LBG_UART
J 0
(-4850 3650);
DISPLAY 1.021277 (-4850 3650);
PAINT ORANGE (-4850 3650);
DISPLAY INVISIBLE (-4850 3650);
FORCEPROP 2 LAST ROOM LBG
J 0
(-4850 3600);
DISPLAY 1.021277 (-4850 3600);
PAINT ORANGE (-4850 3600);
DISPLAY INVISIBLE (-4850 3600);
FORCEPROP 2 LAST CDS_LIB mstr_discrete
J 0
(-4900 3450);
PAINT ORANGE (-4900 3450);
DISPLAY INVISIBLE (-4900 3450);
FORCEADD W_VCC_CIRCLE..1
(-2300 2950);
FORCEPROP 3 LASTPIN (-2300 2950) SIG_NAME P5V_VGA_D\g
J 0
(-2290 2960);
DISPLAY 0.659574 (-2290 2960);
PAINT MONO (-2290 2960);
DISPLAY INVISIBLE (-2290 2960);
FORCEPROP 1 LAST HDL_POWER P5V_VGA_D
J 1
(-2279 3025);
DISPLAY 0.872340 (-2279 3025);
PAINT ORANGE (-2279 3025);
FORCEPROP 1 LAST PATH I72
J 0
(-2300 2950);
DISPLAY 0.617021 (-2300 2950);
PAINT GREEN (-2300 2950);
DISPLAY INVISIBLE (-2300 2950);
FORCEPROP 2 LAST CDS_LIB w_power
J 0
(-2300 2950);
PAINT MONO (-2300 2950);
DISPLAY INVISIBLE (-2300 2950);
FORCEPROP 1 LAST CDS_LMAN_SYM_OUTLINE -100,100,100,-100
J 0
(-2300 2950);
DISPLAY 0.468085 (-2300 2950);
PAINT GREEN (-2300 2950);
DISPLAY INVISIBLE (-2300 2950);
FORCEPROP 1 LAST BODY_TYPE PLUMBING
J 0
(-2288 2944);
DISPLAY 0.340426 (-2288 2944);
PAINT GREEN (-2288 2944);
DISPLAY INVISIBLE (-2288 2944);
FORCEADD CAP_A..1
(-3200 2350);
FORCEPROP 0 LAST GROUP AST2500
J 0
(-3147 2110);
DISPLAY 0.638298 (-3147 2110);
PAINT BROWN (-3147 2110);
DISPLAY BOTH (-3147 2110);
FORCEPROP 1 LAST PACK_TYPE 0402V
J 0
(-3150 2150);
DISPLAY 0.617021 (-3150 2150);
PAINT SKYBLUE (-3150 2150);
FORCEPROP 1 LAST VOLTAGE 16V
J 0
(-3150 2350);
DISPLAY 0.617021 (-3150 2350);
PAINT SKYBLUE (-3150 2350);
FORCEPROP 1 LAST PART_NUMBER A36096-030
J 0
(-3150 2200);
DISPLAY 0.617021 (-3150 2200);
PAINT BLUE (-3150 2200);
FORCEPROP 1 LAST VALUE 0.1UF
J 0
(-3150 2400);
DISPLAY 0.617021 (-3150 2400);
PAINT SKYBLUE (-3150 2400);
FORCEPROP 1 LAST TOLERANCE 10%
J 0
(-3150 2300);
DISPLAY 0.617021 (-3150 2300);
PAINT SKYBLUE (-3150 2300);
FORCEPROP 1 LASTPIN (-3200 2450) $PN 1
J 0
(-3190 2430);
DISPLAY 0.617021 (-3190 2430);
PAINT MONO (-3190 2430);
FORCEPROP 1 LASTPIN (-3200 2250) $PN 2
J 0
(-3190 2230);
DISPLAY 0.617021 (-3190 2230);
PAINT MONO (-3190 2230);
FORCEPROP 1 LAST MATERIAL X7R
J 0
(-3150 2250);
DISPLAY 0.617021 (-3150 2250);
PAINT SKYBLUE (-3150 2250);
FORCEPROP 1 LAST LOCATION C25P83
J 0
(-3150 2450);
DISPLAY 0.617021 (-3150 2450);
PAINT AQUA (-3150 2450);
FORCEPROP 2 LAST SEC 1
J 0
(-3150 2550);
DISPLAY 0.936170 (-3150 2550);
PAINT MONO (-3150 2550);
DISPLAY INVISIBLE (-3150 2550);
FORCEPROP 2 LAST SEC_TYPE 0402V
J 0
(-3150 2550);
PAINT MONO (-3150 2550);
DISPLAY INVISIBLE (-3150 2550);
FORCEPROP 2 LAST CDS_SEC 1
J 0
(-3150 2500);
PAINT ORANGE (-3150 2500);
DISPLAY INVISIBLE (-3150 2500);
FORCEPROP 2 LAST CDS_LIB dev_discrete
J 0
(-3200 2350);
PAINT ORANGE (-3200 2350);
DISPLAY INVISIBLE (-3200 2350);
FORCEPROP 2 LAST BOM_COST PROC_SIDEBAND
J 0
(-3200 2350);
PAINT MONO (-3200 2350);
DISPLAY INVISIBLE (-3200 2350);
FORCEPROP 2 LAST ROOM PROC_SIDEBAND
J 0
(-3150 2100);
DISPLAY 0.978723 (-3150 2100);
PAINT ORANGE (-3150 2100);
DISPLAY INVISIBLE (-3150 2100);
FORCEPROP 1 LAST PATH I74
J 0
(-3150 2500);
DISPLAY 0.978723 (-3150 2500);
PAINT WHITE (-3150 2500);
DISPLAY INVISIBLE (-3150 2500);
FORCEPROP 2 LAST CDS_LOCATION C25P83
J 0
(-3150 2450);
DISPLAY 0.617021 (-3150 2450);
PAINT AQUA (-3150 2450);
DISPLAY INVISIBLE (-3150 2450);
FORCEADD GND..1
(-3200 2100);
FORCEPROP 3 LASTPIN (-3200 2150) SIG_NAME GND\g
J 0
(-3190 2160);
DISPLAY 0.659574 (-3190 2160);
PAINT MONO (-3190 2160);
DISPLAY INVISIBLE (-3190 2160);
FORCEPROP 2 LAST CDS_LIB mstr_symbols
J 0
(-3200 2100);
PAINT MONO (-3200 2100);
DISPLAY INVISIBLE (-3200 2100);
FORCEPROP 1 LAST PATH I75
J 0
(-3125 2100);
DISPLAY 0.872340 (-3125 2100);
PAINT AQUA (-3125 2100);
DISPLAY INVISIBLE (-3125 2100);
FORCEPROP 1 LAST VOLTAGE 0.0V
J 0
(-3261 2073);
DISPLAY 0.340426 (-3261 2073);
PAINT SKYBLUE (-3261 2073);
DISPLAY INVISIBLE (-3261 2073);
FORCEPROP 1 LAST SIZE 1B
J 0
(-3166 2091);
DISPLAY 0.872340 (-3166 2091);
PAINT AQUA (-3166 2091);
DISPLAY INVISIBLE (-3166 2091);
FORCEPROP 1 LAST BODY_TYPE PLUMBING
J 0
(-3261 2073);
DISPLAY 0.340426 (-3261 2073);
PAINT GREEN (-3261 2073);
DISPLAY INVISIBLE (-3261 2073);
FORCEPROP 1 LAST HDL_POWER GND
J 0
(-3241 2291);
DISPLAY 0.872340 (-3241 2291);
PAINT GREEN (-3241 2291);
DISPLAY INVISIBLE (-3241 2291);
FORCEADD IND-68NH-15-GP..1
R 1
(-3650 3600);
FORCEPROP 1 LAST LOCATION L25W1
J 0
(-3985 3625);
DISPLAY 0.617021 (-3985 3625);
PAINT GREEN (-3985 3625);
FORCEPROP 2 LAST RATED 300MA
J 0
(-3850 3500);
DISPLAY 0.638298 (-3850 3500);
PAINT GREEN (-3850 3500);
FORCEPROP 2 LASTPIN (-3500 3600) $PN 2
J 2
(-3465 3615);
DISPLAY 0.808511 (-3465 3615);
PAINT ORANGE (-3465 3615);
FORCEPROP 2 LAST PACK_SIZE DCR=800MOHM
J 0
(-3650 3550);
DISPLAY 0.638298 (-3650 3550);
PAINT GREEN (-3650 3550);
FORCEPROP 1 LAST VALUE IND-68NH-15-GP
J 0
(-3445 3625);
DISPLAY 0.617021 (-3445 3625);
PAINT GREEN (-3445 3625);
FORCEPROP 2 LAST ATTRIBUTE 68NH
J 0
(-3850 3550);
DISPLAY 0.638298 (-3850 3550);
PAINT GREEN (-3850 3550);
FORCEPROP 2 LASTPIN (-3800 3600) $PN 1
J 0
(-3835 3615);
DISPLAY 0.808511 (-3835 3615);
PAINT ORANGE (-3835 3615);
FORCEPROP 0 LAST GROUP AST2500
J 0
(-3647 3510);
DISPLAY 0.638298 (-3647 3510);
PAINT BROWN (-3647 3510);
DISPLAY BOTH (-3647 3510);
FORCEPROP 1 LAST PACK_TYPE DISCRET-GC1
R 1
J 0
(-3650 3600);
DISPLAY 0.617021 (-3650 3600);
PAINT GREEN (-3650 3600);
DISPLAY INVISIBLE (-3650 3600);
FORCEPROP 2 LAST SEC 1
R 1
J 0
(-3800 3625);
DISPLAY 0.680851 (-3800 3625);
PAINT MONO (-3800 3625);
DISPLAY INVISIBLE (-3800 3625);
FORCEPROP 2 LAST SEC_TYPE DISCRET-GC1
R 1
J 0
(-3800 3625);
DISPLAY 1.021277 (-3800 3625);
PAINT ORANGE (-3800 3625);
DISPLAY INVISIBLE (-3800 3625);
FORCEPROP 1 LAST PART_NUMBER 68.6803N.10D
R 1
J 0
(-3650 3600);
DISPLAY 0.617021 (-3650 3600);
PAINT GREEN (-3650 3600);
DISPLAY INVISIBLE (-3650 3600);
FORCEPROP 2 LAST CDS_LIB w_hdl
R 1
J 0
(-3650 3600);
PAINT MONO (-3650 3600);
DISPLAY INVISIBLE (-3650 3600);
FORCEPROP 1 LAST PATH I76
R 1
J 0
(-3650 3600);
DISPLAY 0.617021 (-3650 3600);
PAINT GREEN (-3650 3600);
DISPLAY INVISIBLE (-3650 3600);
FORCEPROP 1 LAST CDS_LMAN_SYM_OUTLINE -50,100,50,-100
R 1
J 0
(-3650 3600);
DISPLAY 0.468085 (-3650 3600);
PAINT GREEN (-3650 3600);
DISPLAY INVISIBLE (-3650 3600);
FORCEADD IND-68NH-15-GP..1
R 1
(-3650 3750);
FORCEPROP 2 LAST ATTRIBUTE 68NH
J 0
(-3850 3700);
DISPLAY 0.638298 (-3850 3700);
PAINT GREEN (-3850 3700);
FORCEPROP 2 LAST RATED 300MA
J 0
(-3850 3650);
DISPLAY 0.638298 (-3850 3650);
PAINT GREEN (-3850 3650);
FORCEPROP 1 LAST VALUE IND-68NH-15-GP
J 0
(-3445 3775);
DISPLAY 0.617021 (-3445 3775);
PAINT GREEN (-3445 3775);
FORCEPROP 2 LASTPIN (-3800 3750) $PN 1
J 0
(-3835 3765);
DISPLAY 0.808511 (-3835 3765);
PAINT ORANGE (-3835 3765);
FORCEPROP 2 LAST PACK_SIZE DCR=800MOHM
J 0
(-3650 3700);
DISPLAY 0.638298 (-3650 3700);
PAINT GREEN (-3650 3700);
FORCEPROP 2 LASTPIN (-3500 3750) $PN 2
J 2
(-3465 3765);
DISPLAY 0.808511 (-3465 3765);
PAINT ORANGE (-3465 3765);
FORCEPROP 1 LAST LOCATION L25W2
J 0
(-3985 3775);
DISPLAY 0.617021 (-3985 3775);
PAINT GREEN (-3985 3775);
FORCEPROP 0 LAST GROUP AST2500
J 0
(-3647 3660);
DISPLAY 0.638298 (-3647 3660);
PAINT BROWN (-3647 3660);
DISPLAY BOTH (-3647 3660);
FORCEPROP 1 LAST CDS_LMAN_SYM_OUTLINE -50,100,50,-100
R 1
J 0
(-3650 3750);
DISPLAY 0.468085 (-3650 3750);
PAINT GREEN (-3650 3750);
DISPLAY INVISIBLE (-3650 3750);
FORCEPROP 2 LAST CDS_LIB w_hdl
R 1
J 0
(-3650 3750);
PAINT MONO (-3650 3750);
DISPLAY INVISIBLE (-3650 3750);
FORCEPROP 1 LAST PART_NUMBER 68.6803N.10D
R 1
J 0
(-3650 3750);
DISPLAY 0.617021 (-3650 3750);
PAINT GREEN (-3650 3750);
DISPLAY INVISIBLE (-3650 3750);
FORCEPROP 2 LAST SEC_TYPE DISCRET-GC1
R 1
J 0
(-3800 3775);
DISPLAY 1.021277 (-3800 3775);
PAINT ORANGE (-3800 3775);
DISPLAY INVISIBLE (-3800 3775);
FORCEPROP 2 LAST SEC 1
R 1
J 0
(-3800 3775);
DISPLAY 0.680851 (-3800 3775);
PAINT MONO (-3800 3775);
DISPLAY INVISIBLE (-3800 3775);
FORCEPROP 1 LAST PACK_TYPE DISCRET-GC1
R 1
J 0
(-3650 3750);
DISPLAY 0.617021 (-3650 3750);
PAINT GREEN (-3650 3750);
DISPLAY INVISIBLE (-3650 3750);
FORCEPROP 1 LAST PATH I77
R 1
J 0
(-3650 3750);
DISPLAY 0.617021 (-3650 3750);
PAINT GREEN (-3650 3750);
DISPLAY INVISIBLE (-3650 3750);
FORCEADD IND-68NH-15-GP..1
R 1
(-3600 3900);
FORCEPROP 1 LAST VALUE IND-68NH-15-GP
J 0
(-3395 3925);
DISPLAY 0.617021 (-3395 3925);
PAINT GREEN (-3395 3925);
FORCEPROP 2 LAST PACK_SIZE DCR=800MOHM
J 0
(-3650 3850);
DISPLAY 0.638298 (-3650 3850);
PAINT GREEN (-3650 3850);
FORCEPROP 0 LAST GROUP AST2500
J 0
(-3647 3810);
DISPLAY 0.638298 (-3647 3810);
PAINT BROWN (-3647 3810);
DISPLAY BOTH (-3647 3810);
FORCEPROP 1 LAST LOCATION L25W3
J 0
(-3985 3925);
DISPLAY 0.617021 (-3985 3925);
PAINT GREEN (-3985 3925);
FORCEPROP 2 LAST ATTRIBUTE 68NH
J 0
(-3850 3850);
DISPLAY 0.638298 (-3850 3850);
PAINT GREEN (-3850 3850);
FORCEPROP 2 LASTPIN (-3750 3900) $PN 1
J 0
(-3785 3915);
DISPLAY 0.808511 (-3785 3915);
PAINT ORANGE (-3785 3915);
FORCEPROP 2 LASTPIN (-3450 3900) $PN 2
J 2
(-3415 3915);
DISPLAY 0.808511 (-3415 3915);
PAINT ORANGE (-3415 3915);
FORCEPROP 2 LAST RATED 300MA
J 0
(-3850 3800);
DISPLAY 0.638298 (-3850 3800);
PAINT GREEN (-3850 3800);
FORCEPROP 1 LAST CDS_LMAN_SYM_OUTLINE -50,100,50,-100
R 1
J 0
(-3600 3900);
DISPLAY 0.468085 (-3600 3900);
PAINT GREEN (-3600 3900);
DISPLAY INVISIBLE (-3600 3900);
FORCEPROP 2 LAST CDS_LIB w_hdl
R 1
J 0
(-3600 3900);
PAINT MONO (-3600 3900);
DISPLAY INVISIBLE (-3600 3900);
FORCEPROP 1 LAST PART_NUMBER 68.6803N.10D
R 1
J 0
(-3600 3900);
DISPLAY 0.617021 (-3600 3900);
PAINT GREEN (-3600 3900);
DISPLAY INVISIBLE (-3600 3900);
FORCEPROP 2 LAST SEC_TYPE DISCRET-GC1
R 1
J 0
(-3750 3925);
DISPLAY 1.021277 (-3750 3925);
PAINT ORANGE (-3750 3925);
DISPLAY INVISIBLE (-3750 3925);
FORCEPROP 2 LAST SEC 1
R 1
J 0
(-3750 3925);
DISPLAY 0.680851 (-3750 3925);
PAINT MONO (-3750 3925);
DISPLAY INVISIBLE (-3750 3925);
FORCEPROP 1 LAST PACK_TYPE DISCRET-GC1
R 1
J 0
(-3600 3900);
DISPLAY 0.617021 (-3600 3900);
PAINT GREEN (-3600 3900);
DISPLAY INVISIBLE (-3600 3900);
FORCEPROP 1 LAST PATH I78
R 1
J 0
(-3600 3900);
DISPLAY 0.617021 (-3600 3900);
PAINT GREEN (-3600 3900);
DISPLAY INVISIBLE (-3600 3900);
FORCEADD GND..1
(-4900 3200);
FORCEPROP 3 LASTPIN (-4900 3250) SIG_NAME GND\g
J 0
(-4890 3260);
DISPLAY 0.659574 (-4890 3260);
PAINT MONO (-4890 3260);
DISPLAY INVISIBLE (-4890 3260);
FORCEPROP 1 LAST SIZE 1B
J 0
(-4866 3191);
DISPLAY 0.872340 (-4866 3191);
PAINT AQUA (-4866 3191);
DISPLAY INVISIBLE (-4866 3191);
FORCEPROP 1 LAST VOLTAGE 0.0V
J 0
(-4961 3173);
DISPLAY 0.340426 (-4961 3173);
PAINT SKYBLUE (-4961 3173);
DISPLAY INVISIBLE (-4961 3173);
FORCEPROP 1 LAST PATH I8
J 0
(-4825 3200);
DISPLAY 0.872340 (-4825 3200);
PAINT AQUA (-4825 3200);
DISPLAY INVISIBLE (-4825 3200);
FORCEPROP 2 LAST CDS_LIB mstr_symbols
J 0
(-4900 3200);
PAINT MONO (-4900 3200);
DISPLAY INVISIBLE (-4900 3200);
FORCEPROP 1 LAST BODY_TYPE PLUMBING
J 0
(-4961 3173);
DISPLAY 0.340426 (-4961 3173);
PAINT GREEN (-4961 3173);
DISPLAY INVISIBLE (-4961 3173);
FORCEPROP 1 LAST HDL_POWER GND
J 0
(-4941 3391);
DISPLAY 0.872340 (-4941 3391);
PAINT GREEN (-4941 3391);
DISPLAY INVISIBLE (-4941 3391);
FORCEADD POLYSW-D5A6V-2-GP-U..1
(-2775 2850);
FORCEPROP 1 LAST VALUE POLYSW-D5A6V-2-GP-U
J 0
(-2900 2750);
DISPLAY 0.617021 (-2900 2750);
PAINT GREEN (-2900 2750);
FORCEPROP 0 LAST CONFIG 069.50007.0071
J 0
(-2997 2710);
DISPLAY 0.638298 (-2997 2710);
PAINT BROWN (-2997 2710);
DISPLAY BOTH (-2997 2710);
FORCEPROP 0 LAST GROUP AST2500
J 0
(-2975 2675);
DISPLAY 0.638298 (-2975 2675);
PAINT BROWN (-2975 2675);
DISPLAY BOTH (-2975 2675);
FORCEPROP 2 LASTPIN (-2950 2850) $PN 1
J 2
(-2960 2860);
DISPLAY 0.808511 (-2960 2860);
PAINT ORANGE (-2960 2860);
FORCEPROP 1 LAST LOCATION F25W1
J 0
(-2900 2925);
DISPLAY 0.617021 (-2900 2925);
PAINT GREEN (-2900 2925);
FORCEPROP 2 LASTPIN (-2600 2850) $PN 2
J 0
(-2590 2860);
DISPLAY 0.808511 (-2590 2860);
PAINT ORANGE (-2590 2860);
FORCEPROP 1 LAST CDS_LMAN_SYM_OUTLINE -125,50,125,-50
J 0
(-2775 2850);
DISPLAY 0.468085 (-2775 2850);
PAINT GREEN (-2775 2850);
DISPLAY INVISIBLE (-2775 2850);
FORCEPROP 1 LAST PATH I89
J 0
(-2775 2850);
DISPLAY 0.617021 (-2775 2850);
PAINT GREEN (-2775 2850);
DISPLAY INVISIBLE (-2775 2850);
FORCEPROP 2 LAST CDS_LIB w_hdl
J 0
(-2775 2850);
PAINT MONO (-2775 2850);
DISPLAY INVISIBLE (-2775 2850);
FORCEPROP 1 LAST PART_NUMBER 69.50011.051
J 0
(-2775 2850);
DISPLAY 0.617021 (-2775 2850);
PAINT GREEN (-2775 2850);
DISPLAY INVISIBLE (-2775 2850);
FORCEPROP 2 LAST SEC_TYPE DISCRET-GA1
J 0
(-2900 2975);
DISPLAY 1.021277 (-2900 2975);
PAINT ORANGE (-2900 2975);
DISPLAY INVISIBLE (-2900 2975);
FORCEPROP 2 LAST SEC 1
J 0
(-2900 2975);
DISPLAY 0.680851 (-2900 2975);
PAINT MONO (-2900 2975);
DISPLAY INVISIBLE (-2900 2975);
FORCEPROP 1 LAST PACK_TYPE DISCRET-GA1
J 0
(-2775 2850);
DISPLAY 0.617021 (-2775 2850);
PAINT GREEN (-2775 2850);
DISPLAY INVISIBLE (-2775 2850);
FORCEADD GND..1
(-4500 3200);
FORCEPROP 3 LASTPIN (-4500 3250) SIG_NAME GND\g
J 0
(-4490 3260);
DISPLAY 0.659574 (-4490 3260);
PAINT MONO (-4490 3260);
DISPLAY INVISIBLE (-4490 3260);
FORCEPROP 2 LAST CDS_LIB mstr_symbols
J 0
(-4500 3200);
PAINT MONO (-4500 3200);
DISPLAY INVISIBLE (-4500 3200);
FORCEPROP 1 LAST PATH I9
J 0
(-4425 3200);
DISPLAY 0.872340 (-4425 3200);
PAINT AQUA (-4425 3200);
DISPLAY INVISIBLE (-4425 3200);
FORCEPROP 1 LAST VOLTAGE 0.0V
J 0
(-4561 3173);
DISPLAY 0.340426 (-4561 3173);
PAINT SKYBLUE (-4561 3173);
DISPLAY INVISIBLE (-4561 3173);
FORCEPROP 1 LAST SIZE 1B
J 0
(-4466 3191);
DISPLAY 0.872340 (-4466 3191);
PAINT AQUA (-4466 3191);
DISPLAY INVISIBLE (-4466 3191);
FORCEPROP 1 LAST BODY_TYPE PLUMBING
J 0
(-4561 3173);
DISPLAY 0.340426 (-4561 3173);
PAINT GREEN (-4561 3173);
DISPLAY INVISIBLE (-4561 3173);
FORCEPROP 1 LAST HDL_POWER GND
J 0
(-4541 3391);
DISPLAY 0.872340 (-4541 3391);
PAINT GREEN (-4541 3391);
DISPLAY INVISIBLE (-4541 3391);
FORCEADD W_VCC_CIRCLE..1
(-4150 2800);
FORCEPROP 3 LASTPIN (-4150 2800) SIG_NAME P5V_VGA_D\g
J 0
(-4140 2810);
DISPLAY 0.659574 (-4140 2810);
PAINT MONO (-4140 2810);
DISPLAY INVISIBLE (-4140 2810);
FORCEPROP 1 LAST HDL_POWER P5V_VGA_D
J 1
(-4129 2875);
DISPLAY 0.872340 (-4129 2875);
PAINT ORANGE (-4129 2875);
FORCEPROP 1 LAST CDS_LMAN_SYM_OUTLINE -100,100,100,-100
J 0
(-4150 2800);
DISPLAY 0.468085 (-4150 2800);
PAINT GREEN (-4150 2800);
DISPLAY INVISIBLE (-4150 2800);
FORCEPROP 2 LAST CDS_LIB w_power
J 0
(-4150 2800);
PAINT MONO (-4150 2800);
DISPLAY INVISIBLE (-4150 2800);
FORCEPROP 1 LAST PATH I91
J 0
(-4150 2800);
DISPLAY 0.617021 (-4150 2800);
PAINT GREEN (-4150 2800);
DISPLAY INVISIBLE (-4150 2800);
FORCEPROP 1 LAST BODY_TYPE PLUMBING
J 0
(-4138 2794);
DISPLAY 0.340426 (-4138 2794);
PAINT GREEN (-4138 2794);
DISPLAY INVISIBLE (-4138 2794);
FORCEADD FET_N_DUAL..5
R 5
(-8100 4750);
FORCEPROP 0 LAST GROUP AST2500
J 0
(-8050 4550);
DISPLAY 0.638298 (-8050 4550);
PAINT BROWN (-8050 4550);
DISPLAY BOTH (-8050 4550);
FORCEPROP 1 LAST VALUE 2N7002DW
J 0
(-8300 4500);
DISPLAY 0.617021 (-8300 4500);
PAINT SKYBLUE (-8300 4500);
FORCEPROP 1 LAST LOCATION Q25W4
J 0
(-8300 4550);
DISPLAY 0.617021 (-8300 4550);
PAINT AQUA (-8300 4550);
FORCEPROP 1 LASTPIN (-8300 4750) $PN 1
J 2
(-8275 4692);
DISPLAY 0.872340 (-8275 4692);
PAINT WHITE (-8275 4692);
FORCEPROP 1 LASTPIN (-7900 4750) $PN 6
J 2
(-7885 4697);
DISPLAY 0.872340 (-7885 4697);
PAINT WHITE (-7885 4697);
FORCEPROP 1 LASTPIN (-8200 4950) $PN 2
J 2
(-8135 4922);
DISPLAY 0.872340 (-8135 4922);
PAINT WHITE (-8135 4922);
FORCEPROP 1 LAST PART_NUMBER D24280-001
J 0
(-8300 4400);
DISPLAY 0.617021 (-8300 4400);
PAINT BLUE (-8300 4400);
FORCEPROP 1 LAST MATERIAL FET
J 0
(-8300 4450);
DISPLAY 0.617021 (-8300 4450);
PAINT SKYBLUE (-8300 4450);
FORCEPROP 2 LAST SEC_TYPE SMLF
R 3
J 0
(-8000 4550);
DISPLAY 1.021277 (-8000 4550);
PAINT ORANGE (-8000 4550);
DISPLAY INVISIBLE (-8000 4550);
FORCEPROP 2 LAST SEC 1
R 3
J 0
(-8000 4550);
DISPLAY 0.680851 (-8000 4550);
PAINT MONO (-8000 4550);
DISPLAY INVISIBLE (-8000 4550);
FORCEPROP 1 LAST PACK_TYPE SMLF
R 3
J 0
(-8250 4550);
DISPLAY 0.978723 (-8250 4550);
PAINT SKYBLUE (-8250 4550);
DISPLAY INVISIBLE (-8250 4550);
FORCEPROP 2 LAST CDS_LIB mstr_discrete
R 3
J 0
(-8100 4750);
PAINT MONO (-8100 4750);
DISPLAY INVISIBLE (-8100 4750);
FORCEPROP 2 LAST BOM_COST DEBUG
R 3
J 0
(-8000 4550);
DISPLAY 1.021277 (-8000 4550);
PAINT ORANGE (-8000 4550);
DISPLAY INVISIBLE (-8000 4550);
FORCEPROP 2 LAST ROOM UART_MUX
R 3
J 0
(-8050 4550);
DISPLAY 1.021277 (-8050 4550);
PAINT ORANGE (-8050 4550);
DISPLAY INVISIBLE (-8050 4550);
FORCEPROP 0 LAST CDS_SEC 1
R 3
J 0
(-8050 4550);
PAINT MONO (-8050 4550);
DISPLAY INVISIBLE (-8050 4550);
FORCEPROP 1 LAST PATH I95
R 3
J 0
(-8050 4550);
DISPLAY 0.978723 (-8050 4550);
PAINT BLUE (-8050 4550);
DISPLAY INVISIBLE (-8050 4550);
FORCEPROP 0 LAST CDS_LOCATION Q25W4
R 3
J 0
(-8050 4550);
PAINT MONO (-8050 4550);
DISPLAY INVISIBLE (-8050 4550);
FORCEADD FET_N_DUAL..5
R 5
(-8100 3500);
FORCEPROP 0 LAST GROUP AST2500
J 0
(-7975 3350);
DISPLAY 0.638298 (-7975 3350);
PAINT BROWN (-7975 3350);
DISPLAY BOTH (-7975 3350);
FORCEPROP 1 LAST PART_NUMBER D24280-001
J 0
(-8300 3150);
DISPLAY 0.617021 (-8300 3150);
PAINT BLUE (-8300 3150);
FORCEPROP 1 LASTPIN (-7900 3500) $PN 3
J 2
(-7885 3447);
DISPLAY 0.872340 (-7885 3447);
PAINT WHITE (-7885 3447);
FORCEPROP 1 LASTPIN (-8200 3700) $PN 5
J 2
(-8135 3672);
DISPLAY 0.872340 (-8135 3672);
PAINT WHITE (-8135 3672);
FORCEPROP 1 LAST LOCATION Q25W4
J 0
(-8300 3300);
DISPLAY 0.617021 (-8300 3300);
PAINT AQUA (-8300 3300);
FORCEPROP 1 LAST VALUE 2N7002DW
J 0
(-8300 3250);
DISPLAY 0.617021 (-8300 3250);
PAINT SKYBLUE (-8300 3250);
FORCEPROP 1 LAST MATERIAL FET
J 0
(-8300 3200);
DISPLAY 0.617021 (-8300 3200);
PAINT SKYBLUE (-8300 3200);
FORCEPROP 1 LASTPIN (-8300 3500) $PN 4
J 2
(-8275 3442);
DISPLAY 0.872340 (-8275 3442);
PAINT WHITE (-8275 3442);
FORCEPROP 1 LAST PACK_TYPE SMLF
R 3
J 0
(-8250 3300);
DISPLAY 0.978723 (-8250 3300);
PAINT SKYBLUE (-8250 3300);
DISPLAY INVISIBLE (-8250 3300);
FORCEPROP 2 LAST SEC 2
J 0
(-8050 3350);
DISPLAY 0.680851 (-8050 3350);
PAINT MONO (-8050 3350);
DISPLAY INVISIBLE (-8050 3350);
FORCEPROP 2 LAST SEC_TYPE SMLF
J 0
(-8050 3350);
DISPLAY 1.021277 (-8050 3350);
PAINT ORANGE (-8050 3350);
DISPLAY INVISIBLE (-8050 3350);
FORCEPROP 1 LAST PATH I96
R 3
J 0
(-8050 3300);
DISPLAY 0.978723 (-8050 3300);
PAINT BLUE (-8050 3300);
DISPLAY INVISIBLE (-8050 3300);
FORCEPROP 2 LAST CDS_LIB mstr_discrete
R 3
J 0
(-8100 3500);
PAINT MONO (-8100 3500);
DISPLAY INVISIBLE (-8100 3500);
FORCEPROP 2 LAST BOM_COST DEBUG
R 3
J 0
(-8000 3300);
DISPLAY 1.021277 (-8000 3300);
PAINT ORANGE (-8000 3300);
DISPLAY INVISIBLE (-8000 3300);
FORCEPROP 2 LAST ROOM UART_MUX
R 3
J 0
(-8050 3300);
DISPLAY 1.021277 (-8050 3300);
PAINT ORANGE (-8050 3300);
DISPLAY INVISIBLE (-8050 3300);
FORCEPROP 0 LAST CDS_LOCATION Q25W4
R 3
J 0
(-8050 3300);
PAINT MONO (-8050 3300);
DISPLAY INVISIBLE (-8050 3300);
FORCEADD INTEL_CORP_BPAGE..1
(-1475 1625);
FORCEPROP 1 LAST CDS_CON_LAST_MODIFIED Fri Jun 16 17:49:31 2017
J 0
(-2900 1950);
PAINT ORANGE (-2900 1950);
DISPLAY INVISIBLE (-2900 1950);
FORCEPROP 2 LAST CUSTOM_TXT_CDS <XR_PAGE_TITLE>
J 0
(-9365 6875);
DISPLAY 0.638298 (-9365 6875);
PAINT PINK (-9365 6875);
DISPLAY INVISIBLE (-9365 6875);
FORCEPROP 2 LAST CUSTOM_TXT_CDS <CON_LAST_MODIFIED>
J 0
(-5475 1725);
PAINT ORANGE (-5475 1725);
FORCEPROP 2 LAST CUSTOM_TXT_CDS <CURRENT_DESIGN_SHEET> OF <TOTAL_DESIGN_SHEETS>
J 0
(-1975 1650);
PAINT ORANGE (-1975 1650);
FORCEPROP 1 LAST SCH_TITLE VGA
J 0
(-9425 1675);
DISPLAY 2.468085 (-9425 1675);
PAINT ORANGE (-9425 1675);
FORCEPROP 2 LAST CDS_LIB mstr_symbols
J 0
(-1475 1625);
PAINT MONO (-1475 1625);
DISPLAY INVISIBLE (-1475 1625);
FORCEPROP 2 LAST PAGE_BORDER TRUE
J 0
(-9365 6875);
DISPLAY 0.638298 (-9365 6875);
PAINT PINK (-9365 6875);
DISPLAY INVISIBLE (-9365 6875);
FORCEPROP 1 LAST COMMENT_BODY TRUE
J 0
(-1463 1637);
DISPLAY 0.468085 (-1463 1637);
PAINT GREEN (-1463 1637);
DISPLAY INVISIBLE (-1463 1637);
FORCEPROP 2 LAST CDS_XR_PAGE_TITLE CR-252 : @BASEBOARD_FAB2_LIB.BASEBOARD_FAB2(SCH_1):PAGE252
J 0
(-9365 6875);
DISPLAY 0.638298 (-9365 6875);
PAINT PINK (-9365 6875);
DISPLAY INVISIBLE (-9365 6875);
WIRE 16 -1 (-4100 3350)(-4100 3250);
WIRE 16 -1 (-4750 4450)(-4750 4400);
WIRE 16 -1 (-4650 4450)(-4750 4450);
WIRE 16 -1 (-4650 4650)(-4750 4650);
WIRE 16 -1 (-4650 5200)(-4750 5200);
WIRE 16 -1 (-4750 5000)(-4750 4950);
WIRE 16 -1 (-4650 5000)(-4750 5000);
WIRE 16 -1 (-3850 4650)(-3850 4700);
WIRE 16 -1 (-4050 4650)(-3850 4650);
WIRE 16 -1 (-3850 4650)(-3600 4650);
WIRE 16 -1 (-3200 4650)(-3200 4600);
WIRE 16 -1 (-3400 4650)(-3200 4650);
WIRE 16 -1 (-6600 5600)(-6600 5550);
WIRE 16 -1 (-6650 5600)(-6600 5600);
WIRE 16 -1 (-3950 5600)(-3950 5550);
WIRE 16 -1 (-4000 5600)(-3950 5600);
WIRE 16 -1 (-3200 5200)(-3200 5150);
WIRE 16 -1 (-3400 5200)(-3200 5200);
WIRE 16 -1 (-3850 5200)(-3850 5250);
WIRE 16 -1 (-4050 5200)(-3850 5200);
WIRE 16 -1 (-3850 5200)(-3600 5200);
WIRE 16 -1 (-8750 2350)(-8750 2300);
WIRE 16 -1 (-9000 2350)(-8750 2350);
WIRE 16 -1 (-8750 3200)(-8750 3150);
WIRE 16 -1 (-8800 3200)(-8750 3200);
WIRE 16 -1 (-8800 3100)(-8800 3200);
WIRE 16 -1 (-9000 3100)(-8800 3100);
WIRE 16 -1 (-9000 2950)(-8850 2950);
WIRE 16 -1 (-9000 2850)(-8850 2850);
WIRE 16 -1 (-9000 2750)(-8850 2750);
WIRE 16 -1 (-9000 2650)(-8850 2650);
WIRE 16 -1 (-9000 2550)(-8850 2550);
WIRE 16 -1 (-5300 2800)(-5300 2750);
WIRE 16 -1 (-5300 2750)(-4900 2750);
WIRE 16 -1 (-2350 3350)(-2350 3250);
WIRE 16 -1 (-2700 3350)(-2700 3250);
WIRE 16 -1 (-3050 3350)(-3050 3250);
WIRE 16 -1 (-6350 2350)(-6350 2450);
WIRE 16 -1 (-6700 2350)(-6700 2450);
WIRE 16 -1 (-7050 2350)(-7050 2450);
WIRE 16 -1 (-8200 5500)(-8200 5400);
WIRE 16 -1 (-7750 5150)(-7750 5050);
WIRE 16 -1 (-6550 4450)(-6550 4400);
WIRE 16 -1 (-6550 3200)(-6550 3150);
WIRE 16 -1 (-7750 3900)(-7750 3800);
WIRE 16 -1 (-8200 4250)(-8200 4150);
WIRE 16 -1 (-2750 4750)(-2750 4700);
WIRE 16 -1 (-2750 4200)(-2750 4150);
WIRE 16 -1 (-2300 2950)(-2300 2850);
WIRE 16 -1 (-2300 2850)(-2600 2850);
WIRE 16 -1 (-3200 2250)(-3200 2150);
WIRE 16 -1 (-4900 3350)(-4900 3250);
WIRE 16 -1 (-4500 3350)(-4500 3250);
WIRE 16 -1 (-4150 2750)(-4150 2800);
WIRE 16 -1 (-4650 2750)(-4150 2750);
WIRE 3 682 (-6450 5550)(-6450 5450);
WIRE 3 682 (-4700 5550)(-6450 5550);
WIRE 3 682 (-6500 5550)(-6450 5550);
WIRE 68 682 (-5700 4000)(-5700 3150);
WIRE 68 682 (-1850 4000)(-5700 4000);
WIRE 68 682 (-5700 3150)(-1850 3150);
WIRE 68 682 (-1850 3150)(-1850 4000);
WIRE 3 682 (-2050 3100)(-3100 3100);
WIRE 3 682 (-2050 2650)(-2050 3100);
WIRE 3 682 (-3100 3100)(-3100 2650);
WIRE 3 682 (-3100 2650)(-2050 2650);
WIRE 16 -1 (-6500 5750)(-6650 5750);
WIRE 16 -1 (-6500 6200)(-6500 5750);
WIRE 16 -1 (-7500 6200)(-6500 6200);
WIRE 16 -1 (-7500 5750)(-8000 5750);
FORCEPROP 2 LAST SIG_NAME V_IO_G_J
J 0
(-7935 5760);
DISPLAY 0.638298 (-7935 5760);
PAINT ORANGE (-7935 5760);
FORCEPROP 2 LASTPROP $XR0 252 
J 0
(-8096 5750);
DISPLAY 0.638298 (-8096 5750);
PAINT MONO (-8096 5750);
WIRE 16 -1 (-7350 5750)(-7500 5750);
WIRE 16 -1 (-7500 5750)(-7500 6200);
WIRE 3 2175 (-9450 1950)(-1500 1950);
WIRE 3 2175 (-1500 1950)(-1500 6350);
WIRE 3 2175 (-9450 1950)(-9450 6350);
WIRE 3 2175 (-9450 6350)(-1500 6350);
WIRE 16 -1 (-3150 4450)(-2750 4450);
WIRE 16 -1 (-2750 4450)(-2750 4400);
WIRE 16 -1 (-2250 4450)(-2750 4450);
FORCEPROP 2 LAST SIG_NAME V_IO_VSYNC_J
J 0
(-2635 4460);
DISPLAY 0.638298 (-2635 4460);
PAINT ORANGE (-2635 4460);
FORCEPROP 2 LASTPROP $XR0 252 
J 0
(-2220 4450);
DISPLAY 0.638298 (-2220 4450);
PAINT MONO (-2220 4450);
WIRE 16 -1 (-6700 3500)(-6550 3500);
WIRE 16 -1 (-6550 3400)(-6550 3500);
WIRE 16 -1 (-5850 3500)(-6550 3500);
FORCEPROP 2 LAST SIG_NAME V_IBMC_5V_DDC_SDA_J
J 0
(-6485 3510);
DISPLAY 0.638298 (-6485 3510);
PAINT ORANGE (-6485 3510);
FORCEPROP 2 LASTPROP $XR0 252 
J 0
(-5820 3500);
DISPLAY 0.638298 (-5820 3500);
PAINT MONO (-5820 3500);
WIRE 16 -1 (-4100 3900)(-4100 3550);
WIRE 16 -1 (-3750 3900)(-4100 3900);
WIRE 16 -1 (-5350 3900)(-4100 3900);
FORCEPROP 2 LAST SIG_NAME BMC_VGA_RED
J 0
(-5285 3910);
DISPLAY 0.680851 (-5285 3910);
PAINT ORANGE (-5285 3910);
WIRE 16 -1 (-4500 3750)(-4500 3550);
WIRE 16 -1 (-3800 3750)(-4500 3750);
WIRE 16 -1 (-5350 3750)(-4500 3750);
FORCEPROP 2 LAST SIG_NAME BMC_VGA_GREEN
J 0
(-5285 3760);
DISPLAY 0.680851 (-5285 3760);
PAINT ORANGE (-5285 3760);
WIRE 16 -1 (-4900 3550)(-4900 3600);
WIRE 16 -1 (-3800 3600)(-4900 3600);
WIRE 16 -1 (-5350 3600)(-4900 3600);
FORCEPROP 2 LAST SIG_NAME BMC_VGA_BLUE
J 0
(-5285 3610);
DISPLAY 0.680851 (-5285 3610);
PAINT ORANGE (-5285 3610);
WIRE 16 -1 (-3050 3600)(-3050 3550);
WIRE 16 -1 (-3050 3600)(-1900 3600);
FORCEPROP 2 LAST SIG_NAME V_IO_B_J
J 0
(-2285 3610);
DISPLAY 0.638298 (-2285 3610);
PAINT ORANGE (-2285 3610);
FORCEPROP 2 LASTPROP $XR0 252 
J 0
(-1840 3600);
DISPLAY 0.638298 (-1840 3600);
PAINT MONO (-1840 3600);
WIRE 16 -1 (-3500 3600)(-3050 3600);
WIRE 16 -1 (-4050 5000)(-3350 5000);
FORCEPROP 2 LAST SIG_NAME VGA_REAR_HSYNC_S
J 0
(-3935 5010);
DISPLAY 0.638298 (-3935 5010);
PAINT ORANGE (-3935 5010);
FORCEPROP 2 LASTPROP $XRERR UNIQUE?
J 0
(-4175 5010);
DISPLAY 0.638298 (-4175 5010);
PAINT MONO (-4175 5010);
DISPLAY INVISIBLE (-4175 5010);
WIRE 16 -1 (-6650 5800)(-6550 5800);
WIRE 16 -1 (-7450 5800)(-8000 5800);
FORCEPROP 2 LAST SIG_NAME V_IO_R_J
J 0
(-7935 5810);
DISPLAY 0.638298 (-7935 5810);
PAINT ORANGE (-7935 5810);
FORCEPROP 2 LASTPROP $XR0 252 
J 0
(-8096 5800);
DISPLAY 0.638298 (-8096 5800);
PAINT MONO (-8096 5800);
WIRE 16 -1 (-7350 5800)(-7450 5800);
WIRE 16 -1 (-7450 6150)(-7450 5800);
WIRE 16 -1 (-6550 5800)(-6550 6150);
WIRE 16 -1 (-6550 6150)(-7450 6150);
WIRE 16 -1 (-6650 5700)(-6450 5700);
WIRE 16 -1 (-7550 5700)(-8000 5700);
FORCEPROP 2 LAST SIG_NAME V_IO_B_J
J 0
(-7935 5710);
DISPLAY 0.638298 (-7935 5710);
PAINT ORANGE (-7935 5710);
FORCEPROP 2 LASTPROP $XR0 252 
J 0
(-8096 5700);
DISPLAY 0.638298 (-8096 5700);
PAINT MONO (-8096 5700);
WIRE 16 -1 (-7350 5700)(-7550 5700);
WIRE 16 -1 (-7550 6250)(-7550 5700);
WIRE 16 -1 (-6450 5700)(-6450 6250);
WIRE 16 -1 (-6450 6250)(-7550 6250);
WIRE 16 -1 (-4900 5750)(-5700 5750);
FORCEPROP 2 LAST SIG_NAME V_IBMC_5V_DDC_SCL_J
J 0
(-5635 5760);
DISPLAY 0.638298 (-5635 5760);
PAINT ORANGE (-5635 5760);
FORCEPROP 2 LASTPROP $XR0 252 
J 0
(-5796 5750);
DISPLAY 0.638298 (-5796 5750);
PAINT MONO (-5796 5750);
WIRE 16 -1 (-4700 5750)(-4900 5750);
WIRE 16 -1 (-4900 6250)(-4900 5750);
WIRE 16 -1 (-3800 6250)(-4900 6250);
WIRE 16 -1 (-3800 5750)(-3800 6250);
WIRE 16 -1 (-4000 5750)(-3800 5750);
WIRE 16 -1 (-4950 5700)(-5700 5700);
FORCEPROP 2 LAST SIG_NAME V_IBMC_5V_DDC_SDA_J
J 0
(-5635 5710);
DISPLAY 0.638298 (-5635 5710);
PAINT ORANGE (-5635 5710);
FORCEPROP 2 LASTPROP $XR0 252 
J 0
(-5796 5700);
DISPLAY 0.638298 (-5796 5700);
PAINT MONO (-5796 5700);
WIRE 16 -1 (-4700 5700)(-4950 5700);
WIRE 16 -1 (-4950 6300)(-4950 5700);
WIRE 16 -1 (-3750 6300)(-4950 6300);
WIRE 16 -1 (-3750 5700)(-3750 6300);
WIRE 16 -1 (-4000 5700)(-3750 5700);
WIRE 68 682 (-7450 2950)(-7450 2250);
WIRE 68 682 (-6250 2950)(-7450 2950);
WIRE 68 682 (-7450 2250)(-6250 2250);
WIRE 68 682 (-6250 2250)(-6250 2950);
WIRE 3 682 (-8325 4900)(-8325 3400);
WIRE 3 682 (-7800 4900)(-8325 4900);
WIRE 3 682 (-8325 3400)(-7800 3400);
WIRE 3 682 (-7800 3400)(-7800 4900);
WIRE 16 -1 (-8300 3500)(-9050 3500);
FORCEPROP 2 LAST SIG_NAME I2C_BMC_VGA_DDC_SDA
J 0
(-8985 3510);
DISPLAY 0.638298 (-8985 3510);
PAINT ORANGE (-8985 3510);
WIRE 16 -1 (-7900 3500)(-7750 3500);
WIRE 16 -1 (-7750 3500)(-6900 3500);
FORCEPROP 2 LAST SIG_NAME I2C_BMC_VGA_DDC_SDA_G
J 0
(-7610 3510);
DISPLAY 0.638298 (-7610 3510);
PAINT ORANGE (-7610 3510);
FORCEPROP 2 LASTPROP $XRERR UNIQUE?
J 0
(-7850 3510);
DISPLAY 0.638298 (-7850 3510);
PAINT MONO (-7850 3510);
DISPLAY INVISIBLE (-7850 3510);
WIRE 16 -1 (-7750 3600)(-7750 3500);
WIRE 16 -1 (-8200 2800)(-9000 2800);
FORCEPROP 2 LAST SIG_NAME V_IO_B_J
J 0
(-8685 2810);
DISPLAY 0.638298 (-8685 2810);
PAINT ORANGE (-8685 2810);
FORCEPROP 2 LASTPROP $XR0 252 
J 0
(-8170 2800);
DISPLAY 0.638298 (-8170 2800);
PAINT MONO (-8170 2800);
WIRE 16 -1 (-4650 4550)(-5350 4550);
FORCEPROP 2 LAST SIG_NAME BMC_VGA_VSYNC
J 0
(-5285 4560);
DISPLAY 0.638298 (-5285 4560);
PAINT ORANGE (-5285 4560);
WIRE 16 -1 (-9000 3050)(-8200 3050);
FORCEPROP 2 LAST SIG_NAME V_IO_R_J
J 0
(-8685 3060);
DISPLAY 0.638298 (-8685 3060);
PAINT ORANGE (-8685 3060);
FORCEPROP 2 LASTPROP $XR0 252 
J 0
(-8170 3050);
DISPLAY 0.638298 (-8170 3050);
PAINT MONO (-8170 3050);
WIRE 16 -1 (-8200 2600)(-9000 2600);
FORCEPROP 2 LAST SIG_NAME V_IO_HSYNC_J
J 0
(-8685 2610);
DISPLAY 0.638298 (-8685 2610);
PAINT ORANGE (-8685 2610);
FORCEPROP 2 LASTPROP $XR0 252 
J 0
(-8170 2600);
DISPLAY 0.638298 (-8170 2600);
PAINT MONO (-8170 2600);
WIRE 16 -1 (-3200 2550)(-3200 2450);
WIRE 16 -1 (-3200 2550)(-2850 2550);
FORCEPROP 2 LAST SIG_NAME P5V_VGA
J 0
(-3085 2560);
DISPLAY 0.638298 (-3085 2560);
PAINT ORANGE (-3085 2560);
FORCEPROP 2 LASTPROP $XR0 252 
J 0
(-2820 2550);
DISPLAY 0.638298 (-2820 2550);
PAINT MONO (-2820 2550);
WIRE 16 -1 (-3200 2850)(-3200 2550);
WIRE 16 -1 (-2950 2850)(-3200 2850);
WIRE 16 -1 (-4800 5850)(-5700 5850);
FORCEPROP 2 LAST SIG_NAME V_IO_HSYNC_J
J 0
(-5635 5860);
DISPLAY 0.638298 (-5635 5860);
PAINT ORANGE (-5635 5860);
FORCEPROP 2 LASTPROP $XR0 252 
J 0
(-5796 5850);
DISPLAY 0.638298 (-5796 5850);
PAINT MONO (-5796 5850);
WIRE 16 -1 (-4700 5850)(-4800 5850);
WIRE 16 -1 (-4800 6150)(-4800 5850);
WIRE 16 -1 (-3900 6150)(-4800 6150);
WIRE 16 -1 (-4000 5850)(-3900 5850);
WIRE 16 -1 (-3900 5850)(-3900 6150);
WIRE 3 682 (-5400 2950)(-5400 2700);
WIRE 3 682 (-5150 2950)(-5400 2950);
WIRE 3 682 (-5400 2700)(-5150 2700);
WIRE 3 682 (-5150 2700)(-5150 2950);
WIRE 16 -1 (-8300 4750)(-9050 4750);
FORCEPROP 2 LAST SIG_NAME I2C_BMC_VGA_DDC_SCL
J 0
(-8985 4760);
DISPLAY 0.638298 (-8985 4760);
PAINT ORANGE (-8985 4760);
WIRE 16 -1 (-8200 5200)(-8200 4950);
FORCEPROP 2 LAST SIG_NAME Q25W1_GATE
J 0
(-8185 5060);
DISPLAY 0.638298 (-8185 5060);
PAINT ORANGE (-8185 5060);
FORCEPROP 2 LASTPROP $XRERR UNIQUE?
J 0
(-8425 5060);
DISPLAY 0.638298 (-8425 5060);
PAINT MONO (-8425 5060);
DISPLAY INVISIBLE (-8425 5060);
WIRE 16 -1 (-8200 3950)(-8200 3700);
FORCEPROP 2 LAST SIG_NAME Q25W2_GATE
J 0
(-8185 3810);
DISPLAY 0.638298 (-8185 3810);
PAINT ORANGE (-8185 3810);
FORCEPROP 2 LASTPROP $XRERR UNIQUE?
J 0
(-8425 3810);
DISPLAY 0.638298 (-8425 3810);
PAINT MONO (-8425 3810);
DISPLAY INVISIBLE (-8425 3810);
WIRE 16 -1 (-5350 5100)(-4650 5100);
FORCEPROP 2 LAST SIG_NAME BMC_VGA_HSYNC
J 0
(-5285 5110);
DISPLAY 0.638298 (-5285 5110);
PAINT ORANGE (-5285 5110);
WIRE 16 -1 (-4850 5800)(-5700 5800);
FORCEPROP 2 LAST SIG_NAME V_IO_VSYNC_J
J 0
(-5635 5810);
DISPLAY 0.638298 (-5635 5810);
PAINT ORANGE (-5635 5810);
FORCEPROP 2 LASTPROP $XR0 252 
J 0
(-5796 5800);
DISPLAY 0.638298 (-5796 5800);
PAINT MONO (-5796 5800);
WIRE 16 -1 (-4700 5800)(-4850 5800);
WIRE 16 -1 (-4850 6200)(-4850 5800);
WIRE 16 -1 (-3850 6200)(-4850 6200);
WIRE 16 -1 (-4000 5800)(-3850 5800);
WIRE 16 -1 (-3850 5800)(-3850 6200);
WIRE 16 -1 (-9000 2400)(-8200 2400);
FORCEPROP 2 LAST SIG_NAME P5V_VGA
J 0
(-8685 2410);
DISPLAY 0.638298 (-8685 2410);
PAINT ORANGE (-8685 2410);
FORCEPROP 2 LASTPROP $XR0 252 
J 0
(-8170 2400);
DISPLAY 0.638298 (-8170 2400);
PAINT MONO (-8170 2400);
WIRE 16 -1 (-9000 2450)(-8200 2450);
FORCEPROP 2 LAST SIG_NAME V_IBMC_5V_DDC_SCL_J
J 0
(-8685 2460);
DISPLAY 0.638298 (-8685 2460);
PAINT ORANGE (-8685 2460);
FORCEPROP 2 LASTPROP $XR0 252 
J 0
(-8110 2450);
DISPLAY 0.638298 (-8110 2450);
PAINT MONO (-8110 2450);
WIRE 16 -1 (-8200 2500)(-9000 2500);
FORCEPROP 2 LAST SIG_NAME V_IBMC_5V_DDC_SDA_J
J 0
(-8685 2510);
DISPLAY 0.638298 (-8685 2510);
PAINT ORANGE (-8685 2510);
FORCEPROP 2 LASTPROP $XR0 252 
J 0
(-8110 2500);
DISPLAY 0.638298 (-8110 2500);
PAINT MONO (-8110 2500);
WIRE 16 -1 (-8200 2700)(-9000 2700);
FORCEPROP 2 LAST SIG_NAME V_IO_VSYNC_J
J 0
(-8685 2710);
DISPLAY 0.638298 (-8685 2710);
PAINT ORANGE (-8685 2710);
FORCEPROP 2 LASTPROP $XR0 252 
J 0
(-8170 2700);
DISPLAY 0.638298 (-8170 2700);
PAINT MONO (-8170 2700);
WIRE 16 -1 (-9000 2900)(-8200 2900);
FORCEPROP 2 LAST SIG_NAME V_IO_G_J
J 0
(-8685 2910);
DISPLAY 0.638298 (-8685 2910);
PAINT ORANGE (-8685 2910);
FORCEPROP 2 LASTPROP $XR0 252 
J 0
(-8170 2900);
DISPLAY 0.638298 (-8170 2900);
PAINT MONO (-8170 2900);
WIRE 3 2175 (-9400 3350)(-8000 3350);
WIRE 3 2175 (-8000 3350)(-8000 2175);
WIRE 3 2175 (-9400 3350)(-9400 2175);
WIRE 3 2175 (-9400 2175)(-8000 2175);
WIRE 16 -1 (-6550 4650)(-6550 4750);
WIRE 16 -1 (-5850 4750)(-6550 4750);
FORCEPROP 2 LAST SIG_NAME V_IBMC_5V_DDC_SCL_J
J 0
(-6485 4760);
DISPLAY 0.638298 (-6485 4760);
PAINT ORANGE (-6485 4760);
FORCEPROP 2 LASTPROP $XR0 252 
J 0
(-5820 4750);
DISPLAY 0.638298 (-5820 4750);
PAINT MONO (-5820 4750);
WIRE 16 -1 (-6700 4750)(-6550 4750);
WIRE 16 -1 (-7050 2750)(-7400 2750);
FORCEPROP 2 LAST SIG_NAME V_IO_B_J
J 0
(-7335 2760);
DISPLAY 0.638298 (-7335 2760);
PAINT ORANGE (-7335 2760);
FORCEPROP 2 LASTPROP $XR0 252 
J 0
(-7556 2750);
DISPLAY 0.638298 (-7556 2750);
PAINT MONO (-7556 2750);
WIRE 16 -1 (-7050 2650)(-7050 2750);
WIRE 16 -1 (-6700 2800)(-6700 2650);
WIRE 16 -1 (-7400 2800)(-6700 2800);
FORCEPROP 2 LAST SIG_NAME V_IO_G_J
J 0
(-7335 2810);
DISPLAY 0.638298 (-7335 2810);
PAINT ORANGE (-7335 2810);
FORCEPROP 2 LASTPROP $XR0 252 
J 0
(-7556 2800);
DISPLAY 0.638298 (-7556 2800);
PAINT MONO (-7556 2800);
WIRE 16 -1 (-6350 2850)(-6350 2650);
WIRE 16 -1 (-7400 2850)(-6350 2850);
FORCEPROP 2 LAST SIG_NAME V_IO_R_J
J 0
(-7335 2860);
DISPLAY 0.638298 (-7335 2860);
PAINT ORANGE (-7335 2860);
FORCEPROP 2 LASTPROP $XR0 252 
J 0
(-7556 2850);
DISPLAY 0.638298 (-7556 2850);
PAINT MONO (-7556 2850);
WIRE 16 -1 (-7750 4850)(-7750 4750);
WIRE 16 -1 (-7750 4750)(-6900 4750);
FORCEPROP 2 LAST SIG_NAME I2C_BMC_VGA_DDC_SCL_G
J 0
(-7610 4760);
DISPLAY 0.638298 (-7610 4760);
PAINT ORANGE (-7610 4760);
FORCEPROP 2 LASTPROP $XRERR UNIQUE?
J 0
(-7850 4760);
DISPLAY 0.638298 (-7850 4760);
PAINT MONO (-7850 4760);
DISPLAY INVISIBLE (-7850 4760);
WIRE 16 -1 (-7900 4750)(-7750 4750);
WIRE 16 -1 (-4050 4450)(-3350 4450);
FORCEPROP 2 LAST SIG_NAME VGA_REAR_VSYNC_S
J 0
(-3935 4460);
DISPLAY 0.638298 (-3935 4460);
PAINT ORANGE (-3935 4460);
FORCEPROP 2 LASTPROP $XRERR UNIQUE?
J 0
(-4175 4460);
DISPLAY 0.638298 (-4175 4460);
PAINT MONO (-4175 4460);
DISPLAY INVISIBLE (-4175 4460);
WIRE 16 -1 (-2750 5000)(-2750 4950);
WIRE 16 -1 (-2250 5000)(-2750 5000);
FORCEPROP 2 LAST SIG_NAME V_IO_HSYNC_J
J 0
(-2635 5010);
DISPLAY 0.638298 (-2635 5010);
PAINT ORANGE (-2635 5010);
FORCEPROP 2 LASTPROP $XR0 252 
J 0
(-2220 5000);
DISPLAY 0.638298 (-2220 5000);
PAINT MONO (-2220 5000);
WIRE 16 -1 (-3150 5000)(-2750 5000);
WIRE 16 -1 (-2700 3750)(-2700 3550);
WIRE 16 -1 (-2700 3750)(-1900 3750);
FORCEPROP 2 LAST SIG_NAME V_IO_G_J
J 0
(-2285 3760);
DISPLAY 0.638298 (-2285 3760);
PAINT ORANGE (-2285 3760);
FORCEPROP 2 LASTPROP $XR0 252 
J 0
(-1840 3750);
DISPLAY 0.638298 (-1840 3750);
PAINT MONO (-1840 3750);
WIRE 16 -1 (-3500 3750)(-2700 3750);
WIRE 16 -1 (-2350 3900)(-2350 3550);
WIRE 16 -1 (-2350 3900)(-1900 3900);
FORCEPROP 2 LAST SIG_NAME V_IO_R_J
J 0
(-2285 3910);
DISPLAY 0.638298 (-2285 3910);
PAINT ORANGE (-2285 3910);
FORCEPROP 2 LASTPROP $XR0 252 
J 0
(-1840 3900);
DISPLAY 0.638298 (-1840 3900);
PAINT MONO (-1840 3900);
WIRE 16 -1 (-3450 3900)(-2350 3900);
DOT 1 (-6550 3500);
DOT 1 (-7750 4750);
DOT 1 (-7750 3500);
DOT 1 (-3200 2550);
DOT 1 (-6550 4750);
DOT 1 (-2350 3900);
DOT 1 (-2750 5000);
DOT 1 (-7500 5750);
DOT 1 (-7550 5700);
DOT 1 (-4900 5750);
DOT 1 (-4850 5800);
DOT 1 (-4950 5700);
DOT 1 (-4800 5850);
DOT 1 (-6450 5550);
DOT 1 (-3850 4650);
DOT 1 (-4100 3900);
DOT 1 (-3050 3600);
DOT 1 (-2700 3750);
DOT 1 (-4500 3750);
DOT 1 (-4900 3600);
DOT 1 (-7450 5800);
DOT 1 (-2750 4450);
DOT 1 (-3850 5200);
FORCENOTE
CLOSE TO CONNECTOR
(-7425 2975) 0;
DISPLAY LEFT (-7425 2975);
DISPLAY 1.021277 (-7425 2975);
PAINT PURPLE (-7425 2975);
FORCENOTE
PLACE NEAR BMC
(-5350 4025) 0;
DISPLAY LEFT (-5350 4025);
DISPLAY 1.021277 (-5350 4025);
PAINT PURPLE (-5350 4025);
FORCENOTE
TP FAB1 POP WHEN AST2500 0106
(-9225 6450) 0;
DISPLAY LEFT (-9225 6450);
DISPLAY 1.021277 (-9225 6450);
PAINT RED (-9225 6450);
FORCENOTE
TP FAB1 CHANGE FUSE 0428
(-2675 2525) 0;
DISPLAY LEFT (-2675 2525);
DISPLAY 1.021277 (-2675 2525);
PAINT RED (-2675 2525);
FORCENOTE
1.75A 8V
(-2050 2675) 0;
DISPLAY LEFT (-2050 2675);
DISPLAY 1.021277 (-2050 2675);
PAINT PURPLE (-2050 2675);
FORCENOTE
TP FAB1 CHANGE VGA CONNECTOR'S PN 0125
(-9400 2025) 0;
DISPLAY LEFT (-9400 2025);
DISPLAY 1.021277 (-9400 2025);
PAINT RED (-9400 2025);
FORCENOTE
TP FAB1 ADD VGA CONNECTOR 0108
(-9300 2100) 0;
DISPLAY LEFT (-9300 2100);
DISPLAY 1.021277 (-9300 2100);
PAINT RED (-9300 2100);
FORCENOTE
TP FAB1 COMBINED TWO MOS TO A DUAL MOS 0112
(-7775 4125) 0;
DISPLAY LEFT (-7775 4125);
DISPLAY 1.021277 (-7775 4125);
PAINT RED (-7775 4125);
FORCENOTE
TP FAB1 CHANGE VGA POWER SOURCE TO NORMAL SOURCE 0216
(-5425 2550) 0;
DISPLAY LEFT (-5425 2550);
DISPLAY 1.021277 (-5425 2550);
PAINT RED (-5425 2550);
FORCENOTE
TP FAB1 ADD ESD IC CR25W1 AND CR25W2 0115
(-6525 5375) 0;
DISPLAY LEFT (-6525 5375);
DISPLAY 1.021277 (-6525 5375);
PAINT RED (-6525 5375);
FORCENOTE
TP FAB1 ADD SOME PARTS OF VGA CIRCUIT, THE OTHER PARTS ARE WAITING FOR HDL SYMBOL. 0106
(-9225 6525) 0;
DISPLAY LEFT (-9225 6525);
DISPLAY 1.021277 (-9225 6525);
PAINT RED (-9225 6525);
FORCENOTE
TP FAB1 CHANGE FUSE 0111
(-2675 2575) 0;
DISPLAY LEFT (-2675 2575);
DISPLAY 1.021277 (-2675 2575);
PAINT RED (-2675 2575);
FORCENOTE
TP FAB1 ADD VGA VOLTAGE SOURCE CIRCUIT 0114
(-5425 3000) 0;
DISPLAY LEFT (-5425 3000);
DISPLAY 1.021277 (-5425 3000);
PAINT RED (-5425 3000);
QUIT
